FILE_TYPE=LIBRARY_PARTS;
primitive 'EMMITSBURG_REV0P9';
  pin
    'RSVD_J23':
      PIN_NUMBER='(J23,0,0,0,0,0,0,0,0,0,0)';
      OUTPUT_TYPE='(TS,TS)';
      INPUT_LOAD='(-0.01,0.01)';
      OUTPUT_LOAD='(1.0,-1.0)';
    'RSVD_H24':
      PIN_NUMBER='(H24,0,0,0,0,0,0,0,0,0,0)';
      OUTPUT_TYPE='(TS,TS)';
      INPUT_LOAD='(-0.01,0.01)';
      OUTPUT_LOAD='(1.0,-1.0)';
    'XCLK_BIASREF':
      PIN_NUMBER='(N29,0,0,0,0,0,0,0,0,0,0)';
      BIDIRECTIONAL='TRUE';
      INPUT_LOAD='(-0.01,0.01)';
      OUTPUT_LOAD='(1.0,-1.0)';
    'CLKOUT_SRC_N_0':
      PIN_NUMBER='(A16,0,0,0,0,0,0,0,0,0,0)';
      OUTPUT_LOAD='(1.0,-1.0)';
    'CLKOUT_SRC_N_1':
      PIN_NUMBER='(G23,0,0,0,0,0,0,0,0,0,0)';
      OUTPUT_LOAD='(1.0,-1.0)';
    'CLKOUT_SRC_N_10':
      PIN_NUMBER='(J16,0,0,0,0,0,0,0,0,0,0)';
      OUTPUT_LOAD='(1.0,-1.0)';
    'CLKOUT_SRC_N_11':
      PIN_NUMBER='(G16,0,0,0,0,0,0,0,0,0,0)';
      OUTPUT_LOAD='(1.0,-1.0)';
    'CLKOUT_SRC_N_12':
      PIN_NUMBER='(A10,0,0,0,0,0,0,0,0,0,0)';
      OUTPUT_LOAD='(1.0,-1.0)';
    'CLKOUT_SRC_N_13':
      PIN_NUMBER='(A8,0,0,0,0,0,0,0,0,0,0)';
      OUTPUT_LOAD='(1.0,-1.0)';
    'CLKOUT_SRC_N_14':
      PIN_NUMBER='(B7,0,0,0,0,0,0,0,0,0,0)';
      OUTPUT_LOAD='(1.0,-1.0)';
    'CLKOUT_SRC_N_15':
      PIN_NUMBER='(B5,0,0,0,0,0,0,0,0,0,0)';
      OUTPUT_LOAD='(1.0,-1.0)';
    'CLKOUT_SRC_N_16':
      PIN_NUMBER='(A18,0,0,0,0,0,0,0,0,0,0)';
      OUTPUT_LOAD='(1.0,-1.0)';
    'CLKOUT_SRC_N_2':
      PIN_NUMBER='(H21,0,0,0,0,0,0,0,0,0,0)';
      OUTPUT_LOAD='(1.0,-1.0)';
    'CLKOUT_SRC_N_3':
      PIN_NUMBER='(B17,0,0,0,0,0,0,0,0,0,0)';
      OUTPUT_LOAD='(1.0,-1.0)';
    'CLKOUT_SRC_N_4':
      PIN_NUMBER='(B19,0,0,0,0,0,0,0,0,0,0)';
      OUTPUT_LOAD='(1.0,-1.0)';
    'CLKOUT_SRC_N_5':
      PIN_NUMBER='(A12,0,0,0,0,0,0,0,0,0,0)';
      OUTPUT_LOAD='(1.0,-1.0)';
    'CLKOUT_SRC_N_6':
      PIN_NUMBER='(B11,0,0,0,0,0,0,0,0,0,0)';
      OUTPUT_LOAD='(1.0,-1.0)';
    'CLKOUT_SRC_N_7':
      PIN_NUMBER='(A14,0,0,0,0,0,0,0,0,0,0)';
      OUTPUT_LOAD='(1.0,-1.0)';
    'CLKOUT_SRC_N_8':
      PIN_NUMBER='(F18,0,0,0,0,0,0,0,0,0,0)';
      OUTPUT_LOAD='(1.0,-1.0)';
    'CLKOUT_SRC_N_9':
      PIN_NUMBER='(B15,0,0,0,0,0,0,0,0,0,0)';
      OUTPUT_LOAD='(1.0,-1.0)';
    'CLKOUT_SRC_P_0':
      PIN_NUMBER='(C16,0,0,0,0,0,0,0,0,0,0)';
      OUTPUT_LOAD='(1.0,-1.0)';
    'CLKOUT_SRC_P_1':
      PIN_NUMBER='(F21,0,0,0,0,0,0,0,0,0,0)';
      OUTPUT_LOAD='(1.0,-1.0)';
    'CLKOUT_SRC_P_10':
      PIN_NUMBER='(K18,0,0,0,0,0,0,0,0,0,0)';
      OUTPUT_LOAD='(1.0,-1.0)';
    'CLKOUT_SRC_P_11':
      PIN_NUMBER='(H15,0,0,0,0,0,0,0,0,0,0)';
      OUTPUT_LOAD='(1.0,-1.0)';
    'CLKOUT_SRC_P_12':
      PIN_NUMBER='(C10,0,0,0,0,0,0,0,0,0,0)';
      OUTPUT_LOAD='(1.0,-1.0)';
    'CLKOUT_SRC_P_13':
      PIN_NUMBER='(C8,0,0,0,0,0,0,0,0,0,0)';
      OUTPUT_LOAD='(1.0,-1.0)';
    'CLKOUT_SRC_P_14':
      PIN_NUMBER='(D7,0,0,0,0,0,0,0,0,0,0)';
      OUTPUT_LOAD='(1.0,-1.0)';
    'CLKOUT_SRC_P_15':
      PIN_NUMBER='(C6,0,0,0,0,0,0,0,0,0,0)';
      OUTPUT_LOAD='(1.0,-1.0)';
    'CLKOUT_SRC_P_16':
      PIN_NUMBER='(C18,0,0,0,0,0,0,0,0,0,0)';
      OUTPUT_LOAD='(1.0,-1.0)';
    'CLKOUT_SRC_P_2':
      PIN_NUMBER='(K21,0,0,0,0,0,0,0,0,0,0)';
      OUTPUT_LOAD='(1.0,-1.0)';
    'CLKOUT_SRC_P_3':
      PIN_NUMBER='(D17,0,0,0,0,0,0,0,0,0,0)';
      OUTPUT_LOAD='(1.0,-1.0)';
    'CLKOUT_SRC_P_4':
      PIN_NUMBER='(D19,0,0,0,0,0,0,0,0,0,0)';
      OUTPUT_LOAD='(1.0,-1.0)';
    'CLKOUT_SRC_P_5':
      PIN_NUMBER='(C12,0,0,0,0,0,0,0,0,0,0)';
      OUTPUT_LOAD='(1.0,-1.0)';
    'CLKOUT_SRC_P_6':
      PIN_NUMBER='(D11,0,0,0,0,0,0,0,0,0,0)';
      OUTPUT_LOAD='(1.0,-1.0)';
    'CLKOUT_SRC_P_7':
      PIN_NUMBER='(C14,0,0,0,0,0,0,0,0,0,0)';
      OUTPUT_LOAD='(1.0,-1.0)';
    'CLKOUT_SRC_P_8':
      PIN_NUMBER='(H18,0,0,0,0,0,0,0,0,0,0)';
      OUTPUT_LOAD='(1.0,-1.0)';
    'CLKOUT_SRC_P_9':
      PIN_NUMBER='(D15,0,0,0,0,0,0,0,0,0,0)';
      OUTPUT_LOAD='(1.0,-1.0)';
    'PMSYNC_CLK_N_0':
      PIN_NUMBER='(D27,0,0,0,0,0,0,0,0,0,0)';
      OUTPUT_LOAD='(1.0,-1.0)';
    'PMSYNC_CLK_N_1':
      PIN_NUMBER='(C28,0,0,0,0,0,0,0,0,0,0)';
      OUTPUT_LOAD='(1.0,-1.0)';
    'PMSYNC_CLK_P_0':
      PIN_NUMBER='(B27,0,0,0,0,0,0,0,0,0,0)';
      OUTPUT_LOAD='(1.0,-1.0)';
    'PMSYNC_CLK_P_1':
      PIN_NUMBER='(A28,0,0,0,0,0,0,0,0,0,0)';
      OUTPUT_LOAD='(1.0,-1.0)';
    '-REFCLK_INJ_NS':
      PIN_NUMBER='(D25,0,0,0,0,0,0,0,0,0,0)';
      INPUT_LOAD='(-0.01,0.01)';
    'REFCLK_INJ_NS_P':
      PIN_NUMBER='(B25,0,0,0,0,0,0,0,0,0,0)';
      INPUT_LOAD='(-0.01,0.01)';
    '-REFCLK_INJ_S':
      PIN_NUMBER='(D21,0,0,0,0,0,0,0,0,0,0)';
      INPUT_LOAD='(-0.01,0.01)';
    'REFCLK_INJ_S_P':
      PIN_NUMBER='(B21,0,0,0,0,0,0,0,0,0,0)';
      INPUT_LOAD='(-0.01,0.01)';
    'RTCX1':
      PIN_NUMBER='(BE6,0,0,0,0,0,0,0,0,0,0)';
      INPUT_LOAD='(-0.01,0.01)';
    'RTCX2':
      PIN_NUMBER='(BF7,0,0,0,0,0,0,0,0,0,0)';
      OUTPUT_LOAD='(1.0,-1.0)';
    'RTC_EXTCAP':
      PIN_NUMBER='(BF5,0,0,0,0,0,0,0,0,0,0)';
      BIDIRECTIONAL='TRUE';
      INPUT_LOAD='(-0.01,0.01)';
      OUTPUT_LOAD='(1.0,-1.0)';
    'XTAL_IN':
      PIN_NUMBER='(B23,0,0,0,0,0,0,0,0,0,0)';
      INPUT_LOAD='(-0.01,0.01)';
    'XTAL_OUT':
      PIN_NUMBER='(D23,0,0,0,0,0,0,0,0,0,0)';
      OUTPUT_LOAD='(1.0,-1.0)';
    'RSVD_BC40':
      PIN_NUMBER='(0,BC40,0,0,0,0,0,0,0,0,0)';
      OUTPUT_TYPE='(TS,TS)';
      INPUT_LOAD='(-0.01,0.01)';
      OUTPUT_LOAD='(1.0,-1.0)';
    'USB2N_0':
      PIN_NUMBER='(0,AR42,0,0,0,0,0,0,0,0,0)';
      BIDIRECTIONAL='TRUE';
      INPUT_LOAD='(-0.01,0.01)';
      OUTPUT_LOAD='(1.0,-1.0)';
    'USB2N_1':
      PIN_NUMBER='(0,AP43,0,0,0,0,0,0,0,0,0)';
      BIDIRECTIONAL='TRUE';
      INPUT_LOAD='(-0.01,0.01)';
      OUTPUT_LOAD='(1.0,-1.0)';
    'USB2N_10':
      PIN_NUMBER='(0,AY43,0,0,0,0,0,0,0,0,0)';
      BIDIRECTIONAL='TRUE';
      INPUT_LOAD='(-0.01,0.01)';
      OUTPUT_LOAD='(1.0,-1.0)';
    'USB2N_11':
      PIN_NUMBER='(0,AH42,0,0,0,0,0,0,0,0,0)';
      BIDIRECTIONAL='TRUE';
      INPUT_LOAD='(-0.01,0.01)';
      OUTPUT_LOAD='(1.0,-1.0)';
    'USB2N_12':
      PIN_NUMBER='(0,BA42,0,0,0,0,0,0,0,0,0)';
      BIDIRECTIONAL='TRUE';
      INPUT_LOAD='(-0.01,0.01)';
      OUTPUT_LOAD='(1.0,-1.0)';
    'USB2N_13':
      PIN_NUMBER='(0,AG43,0,0,0,0,0,0,0,0,0)';
      BIDIRECTIONAL='TRUE';
      INPUT_LOAD='(-0.01,0.01)';
      OUTPUT_LOAD='(1.0,-1.0)';
    'USB2N_2':
      PIN_NUMBER='(0,AT43,0,0,0,0,0,0,0,0,0)';
      BIDIRECTIONAL='TRUE';
      INPUT_LOAD='(-0.01,0.01)';
      OUTPUT_LOAD='(1.0,-1.0)';
    'USB2N_3':
      PIN_NUMBER='(0,AN42,0,0,0,0,0,0,0,0,0)';
      BIDIRECTIONAL='TRUE';
      INPUT_LOAD='(-0.01,0.01)';
      OUTPUT_LOAD='(1.0,-1.0)';
    'USB2N_4':
      PIN_NUMBER='(0,AU42,0,0,0,0,0,0,0,0,0)';
      BIDIRECTIONAL='TRUE';
      INPUT_LOAD='(-0.01,0.01)';
      OUTPUT_LOAD='(1.0,-1.0)';
    'USB2N_5':
      PIN_NUMBER='(0,AL43,0,0,0,0,0,0,0,0,0)';
      BIDIRECTIONAL='TRUE';
      INPUT_LOAD='(-0.01,0.01)';
      OUTPUT_LOAD='(1.0,-1.0)';
    'USB2N_6':
      PIN_NUMBER='(0,AV43,0,0,0,0,0,0,0,0,0)';
      BIDIRECTIONAL='TRUE';
      INPUT_LOAD='(-0.01,0.01)';
      OUTPUT_LOAD='(1.0,-1.0)';
    'USB2N_7':
      PIN_NUMBER='(0,AK42,0,0,0,0,0,0,0,0,0)';
      BIDIRECTIONAL='TRUE';
      INPUT_LOAD='(-0.01,0.01)';
      OUTPUT_LOAD='(1.0,-1.0)';
    'USB2N_8':
      PIN_NUMBER='(0,AW42,0,0,0,0,0,0,0,0,0)';
      BIDIRECTIONAL='TRUE';
      INPUT_LOAD='(-0.01,0.01)';
      OUTPUT_LOAD='(1.0,-1.0)';
    'USB2N_9':
      PIN_NUMBER='(0,AJ43,0,0,0,0,0,0,0,0,0)';
      BIDIRECTIONAL='TRUE';
      INPUT_LOAD='(-0.01,0.01)';
      OUTPUT_LOAD='(1.0,-1.0)';
    'USB2P_0':
      PIN_NUMBER='(0,AR40,0,0,0,0,0,0,0,0,0)';
      BIDIRECTIONAL='TRUE';
      INPUT_LOAD='(-0.01,0.01)';
      OUTPUT_LOAD='(1.0,-1.0)';
    'USB2P_1':
      PIN_NUMBER='(0,AP41,0,0,0,0,0,0,0,0,0)';
      BIDIRECTIONAL='TRUE';
      INPUT_LOAD='(-0.01,0.01)';
      OUTPUT_LOAD='(1.0,-1.0)';
    'USB2P_10':
      PIN_NUMBER='(0,AY41,0,0,0,0,0,0,0,0,0)';
      BIDIRECTIONAL='TRUE';
      INPUT_LOAD='(-0.01,0.01)';
      OUTPUT_LOAD='(1.0,-1.0)';
    'USB2P_11':
      PIN_NUMBER='(0,AH40,0,0,0,0,0,0,0,0,0)';
      BIDIRECTIONAL='TRUE';
      INPUT_LOAD='(-0.01,0.01)';
      OUTPUT_LOAD='(1.0,-1.0)';
    'USB2P_12':
      PIN_NUMBER='(0,BA40,0,0,0,0,0,0,0,0,0)';
      BIDIRECTIONAL='TRUE';
      INPUT_LOAD='(-0.01,0.01)';
      OUTPUT_LOAD='(1.0,-1.0)';
    'USB2P_13':
      PIN_NUMBER='(0,AG41,0,0,0,0,0,0,0,0,0)';
      BIDIRECTIONAL='TRUE';
      INPUT_LOAD='(-0.01,0.01)';
      OUTPUT_LOAD='(1.0,-1.0)';
    'USB2P_2':
      PIN_NUMBER='(0,AT41,0,0,0,0,0,0,0,0,0)';
      BIDIRECTIONAL='TRUE';
      INPUT_LOAD='(-0.01,0.01)';
      OUTPUT_LOAD='(1.0,-1.0)';
    'USB2P_3':
      PIN_NUMBER='(0,AN40,0,0,0,0,0,0,0,0,0)';
      BIDIRECTIONAL='TRUE';
      INPUT_LOAD='(-0.01,0.01)';
      OUTPUT_LOAD='(1.0,-1.0)';
    'USB2P_4':
      PIN_NUMBER='(0,AU40,0,0,0,0,0,0,0,0,0)';
      BIDIRECTIONAL='TRUE';
      INPUT_LOAD='(-0.01,0.01)';
      OUTPUT_LOAD='(1.0,-1.0)';
    'USB2P_5':
      PIN_NUMBER='(0,AL41,0,0,0,0,0,0,0,0,0)';
      BIDIRECTIONAL='TRUE';
      INPUT_LOAD='(-0.01,0.01)';
      OUTPUT_LOAD='(1.0,-1.0)';
    'USB2P_6':
      PIN_NUMBER='(0,AV41,0,0,0,0,0,0,0,0,0)';
      BIDIRECTIONAL='TRUE';
      INPUT_LOAD='(-0.01,0.01)';
      OUTPUT_LOAD='(1.0,-1.0)';
    'USB2P_7':
      PIN_NUMBER='(0,AK40,0,0,0,0,0,0,0,0,0)';
      BIDIRECTIONAL='TRUE';
      INPUT_LOAD='(-0.01,0.01)';
      OUTPUT_LOAD='(1.0,-1.0)';
    'USB2P_8':
      PIN_NUMBER='(0,AW40,0,0,0,0,0,0,0,0,0)';
      BIDIRECTIONAL='TRUE';
      INPUT_LOAD='(-0.01,0.01)';
      OUTPUT_LOAD='(1.0,-1.0)';
    'USB2P_9':
      PIN_NUMBER='(0,AJ41,0,0,0,0,0,0,0,0,0)';
      BIDIRECTIONAL='TRUE';
      INPUT_LOAD='(-0.01,0.01)';
      OUTPUT_LOAD='(1.0,-1.0)';
    'USB2_COMP':
      PIN_NUMBER='(0,BB41,0,0,0,0,0,0,0,0,0)';
      BIDIRECTIONAL='TRUE';
      INPUT_LOAD='(-0.01,0.01)';
      OUTPUT_LOAD='(1.0,-1.0)';
    'DMI_0_RXN':
      PIN_NUMBER='(0,0,A30,0,0,0,0,0,0,0,0)';
      INPUT_LOAD='(-0.01,0.01)';
    'DMI_0_RXP':
      PIN_NUMBER='(0,0,C30,0,0,0,0,0,0,0,0)';
      INPUT_LOAD='(-0.01,0.01)';
    'DMI_0_TXN':
      PIN_NUMBER='(0,0,K28,0,0,0,0,0,0,0,0)';
      OUTPUT_LOAD='(1.0,-1.0)';
    'DMI_0_TXP':
      PIN_NUMBER='(0,0,H28,0,0,0,0,0,0,0,0)';
      OUTPUT_LOAD='(1.0,-1.0)';
    'DMI_1_RXN':
      PIN_NUMBER='(0,0,B31,0,0,0,0,0,0,0,0)';
      INPUT_LOAD='(-0.01,0.01)';
    'DMI_1_RXP':
      PIN_NUMBER='(0,0,D31,0,0,0,0,0,0,0,0)';
      INPUT_LOAD='(-0.01,0.01)';
    'DMI_1_TXN':
      PIN_NUMBER='(0,0,G29,0,0,0,0,0,0,0,0)';
      OUTPUT_LOAD='(1.0,-1.0)';
    'DMI_1_TXP':
      PIN_NUMBER='(0,0,F28,0,0,0,0,0,0,0,0)';
      OUTPUT_LOAD='(1.0,-1.0)';
    'DMI_2_RXN':
      PIN_NUMBER='(0,0,A32,0,0,0,0,0,0,0,0)';
      INPUT_LOAD='(-0.01,0.01)';
    'DMI_2_RXP':
      PIN_NUMBER='(0,0,C32,0,0,0,0,0,0,0,0)';
      INPUT_LOAD='(-0.01,0.01)';
    'DMI_2_TXN':
      PIN_NUMBER='(0,0,J29,0,0,0,0,0,0,0,0)';
      OUTPUT_LOAD='(1.0,-1.0)';
    'DMI_2_TXP':
      PIN_NUMBER='(0,0,H31,0,0,0,0,0,0,0,0)';
      OUTPUT_LOAD='(1.0,-1.0)';
    'DMI_3_RXN':
      PIN_NUMBER='(0,0,B33,0,0,0,0,0,0,0,0)';
      INPUT_LOAD='(-0.01,0.01)';
    'DMI_3_RXP':
      PIN_NUMBER='(0,0,D33,0,0,0,0,0,0,0,0)';
      INPUT_LOAD='(-0.01,0.01)';
    'DMI_3_TXN':
      PIN_NUMBER='(0,0,L32,0,0,0,0,0,0,0,0)';
      OUTPUT_LOAD='(1.0,-1.0)';
    'DMI_3_TXP':
      PIN_NUMBER='(0,0,K31,0,0,0,0,0,0,0,0)';
      OUTPUT_LOAD='(1.0,-1.0)';
    'DMI_4_SATA_19_PCIE3_19_RXN':
      PIN_NUMBER='(0,0,A34,0,0,0,0,0,0,0,0)';
      INPUT_LOAD='(-0.01,0.01)';
    'DMI_4_SATA_19_PCIE3_19_RXP':
      PIN_NUMBER='(0,0,C34,0,0,0,0,0,0,0,0)';
      INPUT_LOAD='(-0.01,0.01)';
    'DMI_4_SATA_19_PCIE3_19_TXN':
      PIN_NUMBER='(0,0,J32,0,0,0,0,0,0,0,0)';
      OUTPUT_LOAD='(1.0,-1.0)';
    'DMI_4_SATA_19_PCIE3_19_TXP':
      PIN_NUMBER='(0,0,G32,0,0,0,0,0,0,0,0)';
      OUTPUT_LOAD='(1.0,-1.0)';
    'DMI_5_SATA_18_PCIE3_18_RXN':
      PIN_NUMBER='(0,0,B35,0,0,0,0,0,0,0,0)';
      INPUT_LOAD='(-0.01,0.01)';
    'DMI_5_SATA_18_PCIE3_18_RXP':
      PIN_NUMBER='(0,0,D35,0,0,0,0,0,0,0,0)';
      INPUT_LOAD='(-0.01,0.01)';
    'DMI_5_SATA_18_PCIE3_18_TXN':
      PIN_NUMBER='(0,0,G36,0,0,0,0,0,0,0,0)';
      OUTPUT_LOAD='(1.0,-1.0)';
    'DMI_5_SATA_18_PCIE3_18_TXP':
      PIN_NUMBER='(0,0,H34,0,0,0,0,0,0,0,0)';
      OUTPUT_LOAD='(1.0,-1.0)';
    'DMI_6_SATA_17_PCIE3_17_RXN':
      PIN_NUMBER='(0,0,A36,0,0,0,0,0,0,0,0)';
      INPUT_LOAD='(-0.01,0.01)';
    'DMI_6_SATA_17_PCIE3_17_RXP':
      PIN_NUMBER='(0,0,C36,0,0,0,0,0,0,0,0)';
      INPUT_LOAD='(-0.01,0.01)';
    'DMI_6_SATA_17_PCIE3_17_TXN':
      PIN_NUMBER='(0,0,K37,0,0,0,0,0,0,0,0)';
      OUTPUT_LOAD='(1.0,-1.0)';
    'DMI_6_SATA_17_PCIE3_17_TXP':
      PIN_NUMBER='(0,0,J36,0,0,0,0,0,0,0,0)';
      OUTPUT_LOAD='(1.0,-1.0)';
    'DMI_7_SATA_16_PCIE3_16_RXN':
      PIN_NUMBER='(0,0,B37,0,0,0,0,0,0,0,0)';
      INPUT_LOAD='(-0.01,0.01)';
    'DMI_7_SATA_16_PCIE3_16_RXP':
      PIN_NUMBER='(0,0,D37,0,0,0,0,0,0,0,0)';
      INPUT_LOAD='(-0.01,0.01)';
    'DMI_7_SATA_16_PCIE3_16_TXN':
      PIN_NUMBER='(0,0,F37,0,0,0,0,0,0,0,0)';
      OUTPUT_LOAD='(1.0,-1.0)';
    'DMI_7_SATA_16_PCIE3_16_TXP':
      PIN_NUMBER='(0,0,H37,0,0,0,0,0,0,0,0)';
      OUTPUT_LOAD='(1.0,-1.0)';
    'PHY_PCIE3_RCOMPN':
      PIN_NUMBER='(0,0,AP31,0,0,0,0,0,0,0,0)';
      BIDIRECTIONAL='TRUE';
      INPUT_LOAD='(-0.01,0.01)';
      OUTPUT_LOAD='(1.0,-1.0)';
    'PHY_PCIE3_RCOMPP':
      PIN_NUMBER='(0,0,AR29,0,0,0,0,0,0,0,0)';
      BIDIRECTIONAL='TRUE';
      INPUT_LOAD='(-0.01,0.01)';
      OUTPUT_LOAD='(1.0,-1.0)';
    'RSVD_N42':
      PIN_NUMBER='(0,0,N42,0,0,0,0,0,0,0,0)';
      OUTPUT_TYPE='(TS,TS)';
      INPUT_LOAD='(-0.01,0.01)';
      OUTPUT_LOAD='(1.0,-1.0)';
    'RSVD_N40':
      PIN_NUMBER='(0,0,N40,0,0,0,0,0,0,0,0)';
      OUTPUT_TYPE='(TS,TS)';
      INPUT_LOAD='(-0.01,0.01)';
      OUTPUT_LOAD='(1.0,-1.0)';
    'RSVD_D39':
      PIN_NUMBER='(0,0,D39,0,0,0,0,0,0,0,0)';
      OUTPUT_TYPE='(TS,TS)';
      INPUT_LOAD='(-0.01,0.01)';
      OUTPUT_LOAD='(1.0,-1.0)';
    'RSVD_C40':
      PIN_NUMBER='(0,0,C40,0,0,0,0,0,0,0,0)';
      OUTPUT_TYPE='(TS,TS)';
      INPUT_LOAD='(-0.01,0.01)';
      OUTPUT_LOAD='(1.0,-1.0)';
    'SATA_0_PCIE3_0_USB3_0_RXN':
      PIN_NUMBER='(0,0,AE41,0,0,0,0,0,0,0,0)';
      INPUT_LOAD='(-0.01,0.01)';
    'SATA_0_PCIE3_0_USB3_0_RXP':
      PIN_NUMBER='(0,0,AE43,0,0,0,0,0,0,0,0)';
      INPUT_LOAD='(-0.01,0.01)';
    'SATA_0_PCIE3_0_USB3_0_TXN':
      PIN_NUMBER='(0,0,AL32,0,0,0,0,0,0,0,0)';
      OUTPUT_LOAD='(1.0,-1.0)';
    'SATA_0_PCIE3_0_USB3_0_TXP':
      PIN_NUMBER='(0,0,AK31,0,0,0,0,0,0,0,0)';
      OUTPUT_LOAD='(1.0,-1.0)';
    'SATA_10_PCIE3_10_GBE_0_RXN':
      PIN_NUMBER='(0,0,M41,0,0,0,0,0,0,0,0)';
      INPUT_LOAD='(-0.01,0.01)';
    'SATA_10_PCIE3_10_GBE_0_RXP':
      PIN_NUMBER='(0,0,M43,0,0,0,0,0,0,0,0)';
      INPUT_LOAD='(-0.01,0.01)';
    'SATA_10_PCIE3_10_GBE_0_TXN':
      PIN_NUMBER='(0,0,W36,0,0,0,0,0,0,0,0)';
      OUTPUT_LOAD='(1.0,-1.0)';
    'SATA_10_PCIE3_10_GBE_0_TXP':
      PIN_NUMBER='(0,0,Y37,0,0,0,0,0,0,0,0)';
      OUTPUT_LOAD='(1.0,-1.0)';
    'SATA_11_PCIE3_11_RXN':
      PIN_NUMBER='(0,0,L40,0,0,0,0,0,0,0,0)';
      INPUT_LOAD='(-0.01,0.01)';
    'SATA_11_PCIE3_11_RXP':
      PIN_NUMBER='(0,0,L42,0,0,0,0,0,0,0,0)';
      INPUT_LOAD='(-0.01,0.01)';
    'SATA_11_PCIE3_11_TXN':
      PIN_NUMBER='(0,0,T37,0,0,0,0,0,0,0,0)';
      OUTPUT_LOAD='(1.0,-1.0)';
    'SATA_11_PCIE3_11_TXP':
      PIN_NUMBER='(0,0,V37,0,0,0,0,0,0,0,0)';
      OUTPUT_LOAD='(1.0,-1.0)';
    'SATA_12_PCIE3_12_GBE_1_RXN':
      PIN_NUMBER='(0,0,K41,0,0,0,0,0,0,0,0)';
      INPUT_LOAD='(-0.01,0.01)';
    'SATA_12_PCIE3_12_GBE_1_RXP':
      PIN_NUMBER='(0,0,K43,0,0,0,0,0,0,0,0)';
      INPUT_LOAD='(-0.01,0.01)';
    'SATA_12_PCIE3_12_GBE_1_TXN':
      PIN_NUMBER='(0,0,V34,0,0,0,0,0,0,0,0)';
      OUTPUT_LOAD='(1.0,-1.0)';
    'SATA_12_PCIE3_12_GBE_1_TXP':
      PIN_NUMBER='(0,0,U36,0,0,0,0,0,0,0,0)';
      OUTPUT_LOAD='(1.0,-1.0)';
    'SATA_13_PCIE3_13_RXN':
      PIN_NUMBER='(0,0,J40,0,0,0,0,0,0,0,0)';
      INPUT_LOAD='(-0.01,0.01)';
    'SATA_13_PCIE3_13_RXP':
      PIN_NUMBER='(0,0,J42,0,0,0,0,0,0,0,0)';
      INPUT_LOAD='(-0.01,0.01)';
    'SATA_13_PCIE3_13_TXN':
      PIN_NUMBER='(0,0,U32,0,0,0,0,0,0,0,0)';
      OUTPUT_LOAD='(1.0,-1.0)';
    'SATA_13_PCIE3_13_TXP':
      PIN_NUMBER='(0,0,W32,0,0,0,0,0,0,0,0)';
      OUTPUT_LOAD='(1.0,-1.0)';
    'SATA_14_PCIE3_14_GBE_2_RXN':
      PIN_NUMBER='(0,0,H41,0,0,0,0,0,0,0,0)';
      INPUT_LOAD='(-0.01,0.01)';
    'SATA_14_PCIE3_14_GBE_2_RXP':
      PIN_NUMBER='(0,0,H43,0,0,0,0,0,0,0,0)';
      INPUT_LOAD='(-0.01,0.01)';
    'SATA_14_PCIE3_14_GBE_2_TXN':
      PIN_NUMBER='(0,0,R32,0,0,0,0,0,0,0,0)';
      OUTPUT_LOAD='(1.0,-1.0)';
    'SATA_14_PCIE3_14_GBE_2_TXP':
      PIN_NUMBER='(0,0,T34,0,0,0,0,0,0,0,0)';
      OUTPUT_LOAD='(1.0,-1.0)';
    'SATA_15_PCIE3_15_RXN':
      PIN_NUMBER='(0,0,G40,0,0,0,0,0,0,0,0)';
      INPUT_LOAD='(-0.01,0.01)';
    'SATA_15_PCIE3_15_RXP':
      PIN_NUMBER='(0,0,G42,0,0,0,0,0,0,0,0)';
      INPUT_LOAD='(-0.01,0.01)';
    'SATA_15_PCIE3_15_TXN':
      PIN_NUMBER='(0,0,P34,0,0,0,0,0,0,0,0)';
      OUTPUT_LOAD='(1.0,-1.0)';
    'SATA_15_PCIE3_15_TXP':
      PIN_NUMBER='(0,0,N36,0,0,0,0,0,0,0,0)';
      OUTPUT_LOAD='(1.0,-1.0)';
    'SATA_1_PCIE3_1_USB3_1_RXN':
      PIN_NUMBER='(0,0,AD40,0,0,0,0,0,0,0,0)';
      INPUT_LOAD='(-0.01,0.01)';
    'SATA_1_PCIE3_1_USB3_1_RXP':
      PIN_NUMBER='(0,0,AD42,0,0,0,0,0,0,0,0)';
      INPUT_LOAD='(-0.01,0.01)';
    'SATA_1_PCIE3_1_USB3_1_TXN':
      PIN_NUMBER='(0,0,AN36,0,0,0,0,0,0,0,0)';
      OUTPUT_LOAD='(1.0,-1.0)';
    'SATA_1_PCIE3_1_USB3_1_TXP':
      PIN_NUMBER='(0,0,AP34,0,0,0,0,0,0,0,0)';
      OUTPUT_LOAD='(1.0,-1.0)';
    'SATA_2_PCIE3_2_USB3_2_RXN':
      PIN_NUMBER='(0,0,AC41,0,0,0,0,0,0,0,0)';
      INPUT_LOAD='(-0.01,0.01)';
    'SATA_2_PCIE3_2_USB3_2_RXP':
      PIN_NUMBER='(0,0,AC43,0,0,0,0,0,0,0,0)';
      INPUT_LOAD='(-0.01,0.01)';
    'SATA_2_PCIE3_2_USB3_2_TXN':
      PIN_NUMBER='(0,0,AR36,0,0,0,0,0,0,0,0)';
      OUTPUT_LOAD='(1.0,-1.0)';
    'SATA_2_PCIE3_2_USB3_2_TXP':
      PIN_NUMBER='(0,0,AT37,0,0,0,0,0,0,0,0)';
      OUTPUT_LOAD='(1.0,-1.0)';
    'SATA_3_PCIE3_3_USB3_3_RXN':
      PIN_NUMBER='(0,0,AB40,0,0,0,0,0,0,0,0)';
      INPUT_LOAD='(-0.01,0.01)';
    'SATA_3_PCIE3_3_USB3_3_RXP':
      PIN_NUMBER='(0,0,AB42,0,0,0,0,0,0,0,0)';
      INPUT_LOAD='(-0.01,0.01)';
    'SATA_3_PCIE3_3_USB3_3_TXN':
      PIN_NUMBER='(0,0,AK34,0,0,0,0,0,0,0,0)';
      OUTPUT_LOAD='(1.0,-1.0)';
    'SATA_3_PCIE3_3_USB3_3_TXP':
      PIN_NUMBER='(0,0,AM34,0,0,0,0,0,0,0,0)';
      OUTPUT_LOAD='(1.0,-1.0)';
    'SATA_4_PCIE3_4_USB3_4_RXN':
      PIN_NUMBER='(0,0,AA41,0,0,0,0,0,0,0,0)';
      INPUT_LOAD='(-0.01,0.01)';
    'SATA_4_PCIE3_4_USB3_4_RXP':
      PIN_NUMBER='(0,0,AA43,0,0,0,0,0,0,0,0)';
      INPUT_LOAD='(-0.01,0.01)';
    'SATA_4_PCIE3_4_USB3_4_TXN':
      PIN_NUMBER='(0,0,AL36,0,0,0,0,0,0,0,0)';
      OUTPUT_LOAD='(1.0,-1.0)';
    'SATA_4_PCIE3_4_USB3_4_TXP':
      PIN_NUMBER='(0,0,AM37,0,0,0,0,0,0,0,0)';
      OUTPUT_LOAD='(1.0,-1.0)';
    'SATA_5_PCIE3_5_USB3_5_RXN':
      PIN_NUMBER='(0,0,Y40,0,0,0,0,0,0,0,0)';
      INPUT_LOAD='(-0.01,0.01)';
    'SATA_5_PCIE3_5_USB3_5_RXP':
      PIN_NUMBER='(0,0,Y42,0,0,0,0,0,0,0,0)';
      INPUT_LOAD='(-0.01,0.01)';
    'SATA_5_PCIE3_5_USB3_5_TXN':
      PIN_NUMBER='(0,0,AH34,0,0,0,0,0,0,0,0)';
      OUTPUT_LOAD='(1.0,-1.0)';
    'SATA_5_PCIE3_5_USB3_5_TXP':
      PIN_NUMBER='(0,0,AJ32,0,0,0,0,0,0,0,0)';
      OUTPUT_LOAD='(1.0,-1.0)';
    'SATA_6_PCIE3_6_USB3_6_RXN':
      PIN_NUMBER='(0,0,W41,0,0,0,0,0,0,0,0)';
      INPUT_LOAD='(-0.01,0.01)';
    'SATA_6_PCIE3_6_USB3_6_RXP':
      PIN_NUMBER='(0,0,W43,0,0,0,0,0,0,0,0)';
      INPUT_LOAD='(-0.01,0.01)';
    'SATA_6_PCIE3_6_USB3_6_TXN':
      PIN_NUMBER='(0,0,AF37,0,0,0,0,0,0,0,0)';
      OUTPUT_LOAD='(1.0,-1.0)';
    'SATA_6_PCIE3_6_USB3_6_TXP':
      PIN_NUMBER='(0,0,AH37,0,0,0,0,0,0,0,0)';
      OUTPUT_LOAD='(1.0,-1.0)';
    'SATA_7_PCIE3_7_USB3_7_RXN':
      PIN_NUMBER='(0,0,V40,0,0,0,0,0,0,0,0)';
      INPUT_LOAD='(-0.01,0.01)';
    'SATA_7_PCIE3_7_USB3_7_RXP':
      PIN_NUMBER='(0,0,V42,0,0,0,0,0,0,0,0)';
      INPUT_LOAD='(-0.01,0.01)';
    'SATA_7_PCIE3_7_USB3_7_TXN':
      PIN_NUMBER='(0,0,AF34,0,0,0,0,0,0,0,0)';
      OUTPUT_LOAD='(1.0,-1.0)';
    'SATA_7_PCIE3_7_USB3_7_TXP':
      PIN_NUMBER='(0,0,AG36,0,0,0,0,0,0,0,0)';
      OUTPUT_LOAD='(1.0,-1.0)';
    'SATA_8_PCIE3_8_USB3_8_RXN':
      PIN_NUMBER='(0,0,U41,0,0,0,0,0,0,0,0)';
      INPUT_LOAD='(-0.01,0.01)';
    'SATA_8_PCIE3_8_USB3_8_RXP':
      PIN_NUMBER='(0,0,U43,0,0,0,0,0,0,0,0)';
      INPUT_LOAD='(-0.01,0.01)';
    'SATA_8_PCIE3_8_USB3_8_TXN':
      PIN_NUMBER='(0,0,AE36,0,0,0,0,0,0,0,0)';
      OUTPUT_LOAD='(1.0,-1.0)';
    'SATA_8_PCIE3_8_USB3_8_TXP':
      PIN_NUMBER='(0,0,AD37,0,0,0,0,0,0,0,0)';
      OUTPUT_LOAD='(1.0,-1.0)';
    'SATA_9_PCIE3_9_USB3_9_RXN':
      PIN_NUMBER='(0,0,R40,0,0,0,0,0,0,0,0)';
      INPUT_LOAD='(-0.01,0.01)';
    'SATA_9_PCIE3_9_USB3_9_RXP':
      PIN_NUMBER='(0,0,R42,0,0,0,0,0,0,0,0)';
      INPUT_LOAD='(-0.01,0.01)';
    'SATA_9_PCIE3_9_USB3_9_TXN':
      PIN_NUMBER='(0,0,AE32,0,0,0,0,0,0,0,0)';
      OUTPUT_LOAD='(1.0,-1.0)';
    'SATA_9_PCIE3_9_USB3_9_TXP':
      PIN_NUMBER='(0,0,AG32,0,0,0,0,0,0,0,0)';
      OUTPUT_LOAD='(1.0,-1.0)';
    'ACPRESENT':
      PIN_NUMBER='(0,0,0,AN7,0,0,0,0,0,0,0)';
      INPUT_LOAD='(-0.01,0.01)';
    'CPUPWRGD':
      PIN_NUMBER='(0,0,0,G10,0,0,0,0,0,0,0)';
      OUTPUT_LOAD='(1.0,-1.0)';
    '-CPU_CATERR':
      PIN_NUMBER='(0,0,0,F8,0,0,0,0,0,0,0)';
      INPUT_LOAD='(-0.01,0.01)';
    '-CPU_ERR0':
      PIN_NUMBER='(0,0,0,J7,0,0,0,0,0,0,0)';
      INPUT_LOAD='(-0.01,0.01)';
    '-CPU_ERR1':
      PIN_NUMBER='(0,0,0,G7,0,0,0,0,0,0,0)';
      INPUT_LOAD='(-0.01,0.01)';
    '-CPU_ERR2':
      PIN_NUMBER='(0,0,0,L7,0,0,0,0,0,0,0)';
      INPUT_LOAD='(-0.01,0.01)';
    '-CPU_MEMTRIP':
      PIN_NUMBER='(0,0,0,E4,0,0,0,0,0,0,0)';
      INPUT_LOAD='(-0.01,0.01)';
    '-CPU_MSMI':
      PIN_NUMBER='(0,0,0,F11,0,0,0,0,0,0,0)';
      INPUT_LOAD='(-0.01,0.01)';
    '-CPU_PWR_DEBUG':
      PIN_NUMBER='(0,0,0,F5,0,0,0,0,0,0,0)';
      OUTPUT_LOAD='(1.0,-1.0)';
    '-CPU_THRMTRIP':
      PIN_NUMBER='(0,0,0,F3,0,0,0,0,0,0,0)';
      INPUT_LOAD='(-0.01,0.01)';
    'DBG_PMODE':
      PIN_NUMBER='(0,0,0,BE40,0,0,0,0,0,0,0)';
      OUTPUT_LOAD='(1.0,-1.0)';
    'DSW_PWROK':
      PIN_NUMBER='(0,0,0,BE8,0,0,0,0,0,0,0)';
      INPUT_LOAD='(-0.01,0.01)';
    'GPP_O_0':
      PIN_NUMBER='(0,0,0,AN10,0,0,0,0,0,0,0)';
      BIDIRECTIONAL='TRUE';
      INPUT_LOAD='(-0.01,0.01)';
      OUTPUT_LOAD='(1.0,-1.0)';
    'GPP_O_7':
      PIN_NUMBER='(0,0,0,AU10,0,0,0,0,0,0,0)';
      BIDIRECTIONAL='TRUE';
      INPUT_LOAD='(-0.01,0.01)';
      OUTPUT_LOAD='(1.0,-1.0)';
    '-INTRUDER':
      PIN_NUMBER='(0,0,0,BG8,0,0,0,0,0,0,0)';
      INPUT_LOAD='(-0.01,0.01)';
    'JTAGX':
      PIN_NUMBER='(0,0,0,BD35,0,0,0,0,0,0,0)';
      BIDIRECTIONAL='TRUE';
      INPUT_LOAD='(-0.01,0.01)';
      OUTPUT_LOAD='(1.0,-1.0)';
    'JTAG_TCK':
      PIN_NUMBER='(0,0,0,BF35,0,0,0,0,0,0,0)';
      BIDIRECTIONAL='TRUE';
      INPUT_LOAD='(-0.01,0.01)';
      OUTPUT_LOAD='(1.0,-1.0)';
    'JTAG_TDI':
      PIN_NUMBER='(0,0,0,BE38,0,0,0,0,0,0,0)';
      BIDIRECTIONAL='TRUE';
      INPUT_LOAD='(-0.01,0.01)';
      OUTPUT_LOAD='(1.0,-1.0)';
    'JTAG_TDO':
      PIN_NUMBER='(0,0,0,BE36,0,0,0,0,0,0,0)';
      OUTPUT_LOAD='(1.0,-1.0)';
    'JTAG_TMS':
      PIN_NUMBER='(0,0,0,BD37,0,0,0,0,0,0,0)';
      BIDIRECTIONAL='TRUE';
      INPUT_LOAD='(-0.01,0.01)';
      OUTPUT_LOAD='(1.0,-1.0)';
    'LANPHYPC':
      PIN_NUMBER='(0,0,0,AJ7,0,0,0,0,0,0,0)';
      OUTPUT_LOAD='(1.0,-1.0)';
    '-LAN_WAKE':
      PIN_NUMBER='(0,0,0,AU7,0,0,0,0,0,0,0)';
      INPUT_LOAD='(-0.01,0.01)';
    'ME_PECI':
      PIN_NUMBER='(0,0,0,J10,0,0,0,0,0,0,0)';
      BIDIRECTIONAL='TRUE';
      INPUT_LOAD='(-0.01,0.01)';
      OUTPUT_LOAD='(1.0,-1.0)';
    'PCH_PWROK':
      PIN_NUMBER='(0,0,0,BE4,0,0,0,0,0,0,0)';
      INPUT_LOAD='(-0.01,0.01)';
    '-PLTRST_CPU':
      PIN_NUMBER='(0,0,0,M8,0,0,0,0,0,0,0)';
      OUTPUT_LOAD='(1.0,-1.0)';
    '-PRDY':
      PIN_NUMBER='(0,0,0,BB37,0,0,0,0,0,0,0)';
      BIDIRECTIONAL='TRUE';
      INPUT_LOAD='(-0.01,0.01)';
      OUTPUT_LOAD='(1.0,-1.0)';
    '-PREQ':
      PIN_NUMBER='(0,0,0,BF37,0,0,0,0,0,0,0)';
      BIDIRECTIONAL='TRUE';
      INPUT_LOAD='(-0.01,0.01)';
      OUTPUT_LOAD='(1.0,-1.0)';
    '-PWRBTN':
      PIN_NUMBER='(0,0,0,AR10,0,0,0,0,0,0,0)';
      INPUT_LOAD='(-0.01,0.01)';
    '-RSMRST':
      PIN_NUMBER='(0,0,0,BD9,0,0,0,0,0,0,0)';
      INPUT_LOAD='(-0.01,0.01)';
    'RSVD_BG36':
      PIN_NUMBER='(0,0,0,BG36,0,0,0,0,0,0,0)';
      OUTPUT_TYPE='(TS,TS)';
      INPUT_LOAD='(-0.01,0.01)';
      OUTPUT_LOAD='(1.0,-1.0)';
    'RSVD_BF39':
      PIN_NUMBER='(0,0,0,BF39,0,0,0,0,0,0,0)';
      OUTPUT_TYPE='(TS,TS)';
      INPUT_LOAD='(-0.01,0.01)';
      OUTPUT_LOAD='(1.0,-1.0)';
    'RSVD_AV21':
      PIN_NUMBER='(0,0,0,AV21,0,0,0,0,0,0,0)';
      OUTPUT_TYPE='(TS,TS)';
      INPUT_LOAD='(-0.01,0.01)';
      OUTPUT_LOAD='(1.0,-1.0)';
    'RSVD_AW23':
      PIN_NUMBER='(0,0,0,AW26,0,0,0,0,0,0,0)';
      OUTPUT_TYPE='(TS,TS)';
      INPUT_LOAD='(-0.01,0.01)';
      OUTPUT_LOAD='(1.0,-1.0)';
    '-SLP_A':
      PIN_NUMBER='(0,0,0,AM11,0,0,0,0,0,0,0)';
      OUTPUT_LOAD='(1.0,-1.0)';
    '-SLP_LAN':
      PIN_NUMBER='(0,0,0,AK8,0,0,0,0,0,0,0)';
      OUTPUT_LOAD='(1.0,-1.0)';
    '-SLP_S3':
      PIN_NUMBER='(0,0,0,AP8,0,0,0,0,0,0,0)';
      OUTPUT_LOAD='(1.0,-1.0)';
    '-SLP_S4':
      PIN_NUMBER='(0,0,0,AL13,0,0,0,0,0,0,0)';
      OUTPUT_LOAD='(1.0,-1.0)';
    '-SLP_S5':
      PIN_NUMBER='(0,0,0,AJ13,0,0,0,0,0,0,0)';
      OUTPUT_LOAD='(1.0,-1.0)';
    '-SLP_SUS':
      PIN_NUMBER='(0,0,0,AL7,0,0,0,0,0,0,0)';
      OUTPUT_LOAD='(1.0,-1.0)';
    'SUSCLK':
      PIN_NUMBER='(0,0,0,AR7,0,0,0,0,0,0,0)';
      OUTPUT_LOAD='(1.0,-1.0)';
    'SYS_PWROK':
      PIN_NUMBER='(0,0,0,AL10,0,0,0,0,0,0,0)';
      INPUT_LOAD='(-0.01,0.01)';
    '-SYS_RESET':
      PIN_NUMBER='(0,0,0,AJ10,0,0,0,0,0,0,0)';
      INPUT_LOAD='(-0.01,0.01)';
    '-TRIGGER0':
      PIN_NUMBER='(0,0,0,H11,0,0,0,0,0,0,0)';
      BIDIRECTIONAL='TRUE';
      INPUT_LOAD='(-0.01,0.01)';
      OUTPUT_LOAD='(1.0,-1.0)';
    '-TRIGGER1':
      PIN_NUMBER='(0,0,0,K8,0,0,0,0,0,0,0)';
      BIDIRECTIONAL='TRUE';
      INPUT_LOAD='(-0.01,0.01)';
      OUTPUT_LOAD='(1.0,-1.0)';
    '-WAKE':
      PIN_NUMBER='(0,0,0,AH11,0,0,0,0,0,0,0)';
      INPUT_LOAD='(-0.01,0.01)';
    '-GPPC_B_18_HS_UART1_RTS':
      PIN_NUMBER='(0,0,0,0,BD25,0,0,0,0,0,0)';
      BIDIRECTIONAL='TRUE';
      INPUT_LOAD='(-0.01,0.01)';
      OUTPUT_LOAD='(1.0,-1.0)';
    '-GPPC_A_0_ESPI_ALERT0':
      PIN_NUMBER='(0,0,0,0,BG20,0,0,0,0,0,0)';
      BIDIRECTIONAL='TRUE';
      INPUT_LOAD='(-0.01,0.01)';
      OUTPUT_LOAD='(1.0,-1.0)';
    'GPPC_A_10_SRCCLKREQ_N_0':
      PIN_NUMBER='(0,0,0,0,BD17,0,0,0,0,0,0)';
      BIDIRECTIONAL='TRUE';
      INPUT_LOAD='(-0.01,0.01)';
      OUTPUT_LOAD='(1.0,-1.0)';
    'GPPC_A_11_SRCCLKREQ_N_1':
      PIN_NUMBER='(0,0,0,0,BG18,0,0,0,0,0,0)';
      BIDIRECTIONAL='TRUE';
      INPUT_LOAD='(-0.01,0.01)';
      OUTPUT_LOAD='(1.0,-1.0)';
    'GPPC_A_12_SRCCLKREQ_N_2':
      PIN_NUMBER='(0,0,0,0,BG16,0,0,0,0,0,0)';
      BIDIRECTIONAL='TRUE';
      INPUT_LOAD='(-0.01,0.01)';
      OUTPUT_LOAD='(1.0,-1.0)';
    'GPPC_A_13_SRCCLKREQ_N_3':
      PIN_NUMBER='(0,0,0,0,BF15,0,0,0,0,0,0)';
      BIDIRECTIONAL='TRUE';
      INPUT_LOAD='(-0.01,0.01)';
      OUTPUT_LOAD='(1.0,-1.0)';
    'GPPC_A_14_SRCCLKREQ_N_4':
      PIN_NUMBER='(0,0,0,0,BE12,0,0,0,0,0,0)';
      BIDIRECTIONAL='TRUE';
      INPUT_LOAD='(-0.01,0.01)';
      OUTPUT_LOAD='(1.0,-1.0)';
    'GPPC_A_15_SRCCLKREQ_N_5':
      PIN_NUMBER='(0,0,0,0,BE14,0,0,0,0,0,0)';
      BIDIRECTIONAL='TRUE';
      INPUT_LOAD='(-0.01,0.01)';
      OUTPUT_LOAD='(1.0,-1.0)';
    'GPPC_A_16_SRCCLKREQ_N_6':
      PIN_NUMBER='(0,0,0,0,BD11,0,0,0,0,0,0)';
      BIDIRECTIONAL='TRUE';
      INPUT_LOAD='(-0.01,0.01)';
      OUTPUT_LOAD='(1.0,-1.0)';
    'GPPC_A_17_SRCCLKREQ_N_7':
      PIN_NUMBER='(0,0,0,0,BF13,0,0,0,0,0,0)';
      BIDIRECTIONAL='TRUE';
      INPUT_LOAD='(-0.01,0.01)';
      OUTPUT_LOAD='(1.0,-1.0)';
    'GPPC_A_18_SRCCLKREQ_N_8':
      PIN_NUMBER='(0,0,0,0,BF11,0,0,0,0,0,0)';
      BIDIRECTIONAL='TRUE';
      INPUT_LOAD='(-0.01,0.01)';
      OUTPUT_LOAD='(1.0,-1.0)';
    'GPPC_A_19_SRCCLKREQ_N_9':
      PIN_NUMBER='(0,0,0,0,BG14,0,0,0,0,0,0)';
      BIDIRECTIONAL='TRUE';
      INPUT_LOAD='(-0.01,0.01)';
      OUTPUT_LOAD='(1.0,-1.0)';
    '-GPPC_A_1_ESPI_ALERT1':
      PIN_NUMBER='(0,0,0,0,BD15,0,0,0,0,0,0)';
      BIDIRECTIONAL='TRUE';
      INPUT_LOAD='(-0.01,0.01)';
      OUTPUT_LOAD='(1.0,-1.0)';
    'GPPC_A_2_ESPI_IO_0':
      PIN_NUMBER='(0,0,0,0,BG12,0,0,0,0,0,0)';
      BIDIRECTIONAL='TRUE';
      INPUT_LOAD='(-0.01,0.01)';
      OUTPUT_LOAD='(1.0,-1.0)';
    'GPPC_A_3_ESPI_IO_1':
      PIN_NUMBER='(0,0,0,0,BF19,0,0,0,0,0,0)';
      BIDIRECTIONAL='TRUE';
      INPUT_LOAD='(-0.01,0.01)';
      OUTPUT_LOAD='(1.0,-1.0)';
    'GPPC_A_4_ESPI_IO_2':
      PIN_NUMBER='(0,0,0,0,BE18,0,0,0,0,0,0)';
      BIDIRECTIONAL='TRUE';
      INPUT_LOAD='(-0.01,0.01)';
      OUTPUT_LOAD='(1.0,-1.0)';
    'GPPC_A_5_ESPI_IO_3':
      PIN_NUMBER='(0,0,0,0,BD19,0,0,0,0,0,0)';
      BIDIRECTIONAL='TRUE';
      INPUT_LOAD='(-0.01,0.01)';
      OUTPUT_LOAD='(1.0,-1.0)';
    '-GPPC_A_6_ESPI_CS0':
      PIN_NUMBER='(0,0,0,0,BE20,0,0,0,0,0,0)';
      BIDIRECTIONAL='TRUE';
      INPUT_LOAD='(-0.01,0.01)';
      OUTPUT_LOAD='(1.0,-1.0)';
    '-GPPC_A_7_ESPI_CS1':
      PIN_NUMBER='(0,0,0,0,BE16,0,0,0,0,0,0)';
      BIDIRECTIONAL='TRUE';
      INPUT_LOAD='(-0.01,0.01)';
      OUTPUT_LOAD='(1.0,-1.0)';
    '-GPPC_A_8_ESPI_RESET':
      PIN_NUMBER='(0,0,0,0,BF17,0,0,0,0,0,0)';
      BIDIRECTIONAL='TRUE';
      INPUT_LOAD='(-0.01,0.01)';
      OUTPUT_LOAD='(1.0,-1.0)';
    'GPPC_A_9_ESPI_CLK':
      PIN_NUMBER='(0,0,0,0,BD13,0,0,0,0,0,0)';
      BIDIRECTIONAL='TRUE';
      INPUT_LOAD='(-0.01,0.01)';
      OUTPUT_LOAD='(1.0,-1.0)';
    'GPPC_B_0_GSXDOUT':
      PIN_NUMBER='(0,0,0,0,BD33,0,0,0,0,0,0)';
      BIDIRECTIONAL='TRUE';
      INPUT_LOAD='(-0.01,0.01)';
      OUTPUT_LOAD='(1.0,-1.0)';
    'GPPC_B_10_USB2_OCB_5':
      PIN_NUMBER='(0,0,0,0,BG24,0,0,0,0,0,0)';
      BIDIRECTIONAL='TRUE';
      INPUT_LOAD='(-0.01,0.01)';
      OUTPUT_LOAD='(1.0,-1.0)';
    'GPPC_B_11_USB2_OCB_6':
      PIN_NUMBER='(0,0,0,0,BG22,0,0,0,0,0,0)';
      BIDIRECTIONAL='TRUE';
      INPUT_LOAD='(-0.01,0.01)';
      OUTPUT_LOAD='(1.0,-1.0)';
    'GPPC_B_12_HS_UART0_RXD':
      PIN_NUMBER='(0,0,0,0,BD29,0,0,0,0,0,0)';
      BIDIRECTIONAL='TRUE';
      INPUT_LOAD='(-0.01,0.01)';
      OUTPUT_LOAD='(1.0,-1.0)';
    'GPPC_B_13_HS_UART0_TXD':
      PIN_NUMBER='(0,0,0,0,BE28,0,0,0,0,0,0)';
      BIDIRECTIONAL='TRUE';
      INPUT_LOAD='(-0.01,0.01)';
      OUTPUT_LOAD='(1.0,-1.0)';
    '-GPPC_B_14_HS_UART0_RTS':
      PIN_NUMBER='(0,0,0,0,BF29,0,0,0,0,0,0)';
      BIDIRECTIONAL='TRUE';
      INPUT_LOAD='(-0.01,0.01)';
      OUTPUT_LOAD='(1.0,-1.0)';
    '-GPPC_B_15_HS_UART0_CTS':
      PIN_NUMBER='(0,0,0,0,BD27,0,0,0,0,0,0)';
      BIDIRECTIONAL='TRUE';
      INPUT_LOAD='(-0.01,0.01)';
      OUTPUT_LOAD='(1.0,-1.0)';
    'GPPC_B_16_HS_UART1_RXD':
      PIN_NUMBER='(0,0,0,0,BE26,0,0,0,0,0,0)';
      BIDIRECTIONAL='TRUE';
      INPUT_LOAD='(-0.01,0.01)';
      OUTPUT_LOAD='(1.0,-1.0)';
    'GPPC_B_17_HS_UART1_TXD':
      PIN_NUMBER='(0,0,0,0,BF27,0,0,0,0,0,0)';
      BIDIRECTIONAL='TRUE';
      INPUT_LOAD='(-0.01,0.01)';
      OUTPUT_LOAD='(1.0,-1.0)';
    '-GPPC_B_19_HS_UART1_CTS':
      PIN_NUMBER='(0,0,0,0,BF25,0,0,0,0,0,0)';
      BIDIRECTIONAL='TRUE';
      INPUT_LOAD='(-0.01,0.01)';
      OUTPUT_LOAD='(1.0,-1.0)';
    'GPPC_B_1_GSXSLOAD':
      PIN_NUMBER='(0,0,0,0,BE32,0,0,0,0,0,0)';
      BIDIRECTIONAL='TRUE';
      INPUT_LOAD='(-0.01,0.01)';
      OUTPUT_LOAD='(1.0,-1.0)';
    'GPPC_B_20':
      PIN_NUMBER='(0,0,0,0,BE24,0,0,0,0,0,0)';
      BIDIRECTIONAL='TRUE';
      INPUT_LOAD='(-0.01,0.01)';
      OUTPUT_LOAD='(1.0,-1.0)';
    'GPPC_B_21':
      PIN_NUMBER='(0,0,0,0,BF23,0,0,0,0,0,0)';
      BIDIRECTIONAL='TRUE';
      INPUT_LOAD='(-0.01,0.01)';
      OUTPUT_LOAD='(1.0,-1.0)';
    'GPPC_B_22':
      PIN_NUMBER='(0,0,0,0,BE22,0,0,0,0,0,0)';
      BIDIRECTIONAL='TRUE';
      INPUT_LOAD='(-0.01,0.01)';
      OUTPUT_LOAD='(1.0,-1.0)';
    'GPPC_B_23':
      PIN_NUMBER='(0,0,0,0,BD23,0,0,0,0,0,0)';
      BIDIRECTIONAL='TRUE';
      INPUT_LOAD='(-0.01,0.01)';
      OUTPUT_LOAD='(1.0,-1.0)';
    'GPPC_B_2_GSXDIN':
      PIN_NUMBER='(0,0,0,0,BF33,0,0,0,0,0,0)';
      BIDIRECTIONAL='TRUE';
      INPUT_LOAD='(-0.01,0.01)';
      OUTPUT_LOAD='(1.0,-1.0)';
    '-GPPC_B_3_GSXRESET':
      PIN_NUMBER='(0,0,0,0,BD31,0,0,0,0,0,0)';
      BIDIRECTIONAL='TRUE';
      INPUT_LOAD='(-0.01,0.01)';
      OUTPUT_LOAD='(1.0,-1.0)';
    'GPPC_B_4_GSXCLK':
      PIN_NUMBER='(0,0,0,0,BE30,0,0,0,0,0,0)';
      BIDIRECTIONAL='TRUE';
      INPUT_LOAD='(-0.01,0.01)';
      OUTPUT_LOAD='(1.0,-1.0)';
    'GPPC_B_5_USB2_OCB_0':
      PIN_NUMBER='(0,0,0,0,BF31,0,0,0,0,0,0)';
      BIDIRECTIONAL='TRUE';
      INPUT_LOAD='(-0.01,0.01)';
      OUTPUT_LOAD='(1.0,-1.0)';
    'GPPC_B_6_USB2_OCB_1':
      PIN_NUMBER='(0,0,0,0,BG32,0,0,0,0,0,0)';
      BIDIRECTIONAL='TRUE';
      INPUT_LOAD='(-0.01,0.01)';
      OUTPUT_LOAD='(1.0,-1.0)';
    'GPPC_B_7_USB2_OCB_2':
      PIN_NUMBER='(0,0,0,0,BG30,0,0,0,0,0,0)';
      BIDIRECTIONAL='TRUE';
      INPUT_LOAD='(-0.01,0.01)';
      OUTPUT_LOAD='(1.0,-1.0)';
    'GPPC_B_8_USB2_OCB_3':
      PIN_NUMBER='(0,0,0,0,BG28,0,0,0,0,0,0)';
      BIDIRECTIONAL='TRUE';
      INPUT_LOAD='(-0.01,0.01)';
      OUTPUT_LOAD='(1.0,-1.0)';
    'GPPC_B_9_USB2_OCB_4':
      PIN_NUMBER='(0,0,0,0,BG26,0,0,0,0,0,0)';
      BIDIRECTIONAL='TRUE';
      INPUT_LOAD='(-0.01,0.01)';
      OUTPUT_LOAD='(1.0,-1.0)';
    'GPPC_C_0_ME_SML0CLK':
      PIN_NUMBER='(0,0,0,0,BC4,0,0,0,0,0,0)';
      BIDIRECTIONAL='TRUE';
      INPUT_LOAD='(-0.01,0.01)';
      OUTPUT_LOAD='(1.0,-1.0)';
    'GPPC_C_10_ME_SML2DATA':
      PIN_NUMBER='(0,0,0,0,AP3,0,0,0,0,0,0)';
      BIDIRECTIONAL='TRUE';
      INPUT_LOAD='(-0.01,0.01)';
      OUTPUT_LOAD='(1.0,-1.0)';
    '-GPPC_C_11_ME_SML2ALERT':
      PIN_NUMBER='(0,0,0,0,AV3,0,0,0,0,0,0)';
      BIDIRECTIONAL='TRUE';
      INPUT_LOAD='(-0.01,0.01)';
      OUTPUT_LOAD='(1.0,-1.0)';
    'GPPC_C_12_ME_SML3CLK':
      PIN_NUMBER='(0,0,0,0,AN4,0,0,0,0,0,0)';
      BIDIRECTIONAL='TRUE';
      INPUT_LOAD='(-0.01,0.01)';
      OUTPUT_LOAD='(1.0,-1.0)';
    'GPPC_C_13_ME_SML3DATA':
      PIN_NUMBER='(0,0,0,0,AY1,0,0,0,0,0,0)';
      BIDIRECTIONAL='TRUE';
      INPUT_LOAD='(-0.01,0.01)';
      OUTPUT_LOAD='(1.0,-1.0)';
    '-GPPC_C_14_ME_SML3ALERT':
      PIN_NUMBER='(0,0,0,0,AW2,0,0,0,0,0,0)';
      BIDIRECTIONAL='TRUE';
      INPUT_LOAD='(-0.01,0.01)';
      OUTPUT_LOAD='(1.0,-1.0)';
    'GPPC_C_15_ME_SML4CLK':
      PIN_NUMBER='(0,0,0,0,BA2,0,0,0,0,0,0)';
      BIDIRECTIONAL='TRUE';
      INPUT_LOAD='(-0.01,0.01)';
      OUTPUT_LOAD='(1.0,-1.0)';
    'GPPC_C_16_ME_SML4DATA':
      PIN_NUMBER='(0,0,0,0,AV1,0,0,0,0,0,0)';
      BIDIRECTIONAL='TRUE';
      INPUT_LOAD='(-0.01,0.01)';
      OUTPUT_LOAD='(1.0,-1.0)';
    '-GPPC_C_17_ME_SML4ALERT':
      PIN_NUMBER='(0,0,0,0,AL3,0,0,0,0,0,0)';
      BIDIRECTIONAL='TRUE';
      INPUT_LOAD='(-0.01,0.01)';
      OUTPUT_LOAD='(1.0,-1.0)';
    'GPPC_C_18':
      PIN_NUMBER='(0,0,0,0,AL5,0,0,0,0,0,0)';
      BIDIRECTIONAL='TRUE';
      INPUT_LOAD='(-0.01,0.01)';
      OUTPUT_LOAD='(1.0,-1.0)';
    'GPPC_C_19_MC_SMBCLK':
      PIN_NUMBER='(0,0,0,0,AL1,0,0,0,0,0,0)';
      BIDIRECTIONAL='TRUE';
      INPUT_LOAD='(-0.01,0.01)';
      OUTPUT_LOAD='(1.0,-1.0)';
    'GPPC_C_1_ME_SML0DATA':
      PIN_NUMBER='(0,0,0,0,BA4,0,0,0,0,0,0)';
      BIDIRECTIONAL='TRUE';
      INPUT_LOAD='(-0.01,0.01)';
      OUTPUT_LOAD='(1.0,-1.0)';
    'GPPC_C_20_MC_SMBDATA':
      PIN_NUMBER='(0,0,0,0,AT1,0,0,0,0,0,0)';
      BIDIRECTIONAL='TRUE';
      INPUT_LOAD='(-0.01,0.01)';
      OUTPUT_LOAD='(1.0,-1.0)';
    '-GPPC_C_21_MC_SMBALERT':
      PIN_NUMBER='(0,0,0,0,AN2,0,0,0,0,0,0)';
      BIDIRECTIONAL='TRUE';
      INPUT_LOAD='(-0.01,0.01)';
      OUTPUT_LOAD='(1.0,-1.0)';
    '-GPPC_C_2_ME_SML0ALERT':
      PIN_NUMBER='(0,0,0,0,AU2,0,0,0,0,0,0)';
      BIDIRECTIONAL='TRUE';
      INPUT_LOAD='(-0.01,0.01)';
      OUTPUT_LOAD='(1.0,-1.0)';
    'GPPC_C_3_ME_SML0BDATA':
      PIN_NUMBER='(0,0,0,0,AU4,0,0,0,0,0,0)';
      BIDIRECTIONAL='TRUE';
      INPUT_LOAD='(-0.01,0.01)';
      OUTPUT_LOAD='(1.0,-1.0)';
    'GPPC_C_4_ME_SML0BCLK':
      PIN_NUMBER='(0,0,0,0,BB3,0,0,0,0,0,0)';
      BIDIRECTIONAL='TRUE';
      INPUT_LOAD='(-0.01,0.01)';
      OUTPUT_LOAD='(1.0,-1.0)';
    '-GPPC_C_5_ME_SML0BALERT':
      PIN_NUMBER='(0,0,0,0,AT3,0,0,0,0,0,0)';
      BIDIRECTIONAL='TRUE';
      INPUT_LOAD='(-0.01,0.01)';
      OUTPUT_LOAD='(1.0,-1.0)';
    'GPPC_C_6_ME_SML1CLK':
      PIN_NUMBER='(0,0,0,0,AP1,0,0,0,0,0,0)';
      BIDIRECTIONAL='TRUE';
      INPUT_LOAD='(-0.01,0.01)';
      OUTPUT_LOAD='(1.0,-1.0)';
    'GPPC_C_7_ME_SML1DATA':
      PIN_NUMBER='(0,0,0,0,AW4,0,0,0,0,0,0)';
      BIDIRECTIONAL='TRUE';
      INPUT_LOAD='(-0.01,0.01)';
      OUTPUT_LOAD='(1.0,-1.0)';
    '-GPPC_C_8_ME_SML1ALERT':
      PIN_NUMBER='(0,0,0,0,AR4,0,0,0,0,0,0)';
      BIDIRECTIONAL='TRUE';
      INPUT_LOAD='(-0.01,0.01)';
      OUTPUT_LOAD='(1.0,-1.0)';
    'GPPC_C_9_ME_SML2CLK':
      PIN_NUMBER='(0,0,0,0,AR2,0,0,0,0,0,0)';
      BIDIRECTIONAL='TRUE';
      INPUT_LOAD='(-0.01,0.01)';
      OUTPUT_LOAD='(1.0,-1.0)';
    'GPP_D_0_HS_SMBCLK_DMA_SMBCLK':
      PIN_NUMBER='(0,0,0,0,AF2,0,0,0,0,0,0)';
      BIDIRECTIONAL='TRUE';
      INPUT_LOAD='(-0.01,0.01)';
      OUTPUT_LOAD='(1.0,-1.0)';
    '-GPP_D_10_BM_BUSY_N_SX_EXIT_HOLDOFF':
      PIN_NUMBER='(0,0,0,0,AB2,0,0,0,0,0,0)';
      BIDIRECTIONAL='TRUE';
      INPUT_LOAD='(-0.01,0.01)';
      OUTPUT_LOAD='(1.0,-1.0)';
    '-GPP_D_11_PLTRST':
      PIN_NUMBER='(0,0,0,0,AB4,0,0,0,0,0,0)';
      BIDIRECTIONAL='TRUE';
      INPUT_LOAD='(-0.01,0.01)';
      OUTPUT_LOAD='(1.0,-1.0)';
    '-GPP_D_12_PCHHOT':
      PIN_NUMBER='(0,0,0,0,AH2,0,0,0,0,0,0)';
      BIDIRECTIONAL='TRUE';
      INPUT_LOAD='(-0.01,0.01)';
      OUTPUT_LOAD='(1.0,-1.0)';
    'GPP_D_13_ADR_COMPLETE':
      PIN_NUMBER='(0,0,0,0,AC1,0,0,0,0,0,0)';
      BIDIRECTIONAL='TRUE';
      INPUT_LOAD='(-0.01,0.01)';
      OUTPUT_LOAD='(1.0,-1.0)';
    '-GPP_D_14_ADR_TRIGGER':
      PIN_NUMBER='(0,0,0,0,AH4,0,0,0,0,0,0)';
      BIDIRECTIONAL='TRUE';
      INPUT_LOAD='(-0.01,0.01)';
      OUTPUT_LOAD='(1.0,-1.0)';
    '-GPP_D_15_VRALERT':
      PIN_NUMBER='(0,0,0,0,AC3,0,0,0,0,0,0)';
      BIDIRECTIONAL='TRUE';
      INPUT_LOAD='(-0.01,0.01)';
      OUTPUT_LOAD='(1.0,-1.0)';
    'GPP_D_16_ADR_ACK':
      PIN_NUMBER='(0,0,0,0,AD4,0,0,0,0,0,0)';
      BIDIRECTIONAL='TRUE';
      INPUT_LOAD='(-0.01,0.01)';
      OUTPUT_LOAD='(1.0,-1.0)';
    '-GPP_D_17_THERMTRIP':
      PIN_NUMBER='(0,0,0,0,Y2,0,0,0,0,0,0)';
      BIDIRECTIONAL='TRUE';
      INPUT_LOAD='(-0.01,0.01)';
      OUTPUT_LOAD='(1.0,-1.0)';
    '-GPP_D_18_MEMTRIP':
      PIN_NUMBER='(0,0,0,0,AF4,0,0,0,0,0,0)';
      BIDIRECTIONAL='TRUE';
      INPUT_LOAD='(-0.01,0.01)';
      OUTPUT_LOAD='(1.0,-1.0)';
    '-GPP_D_19_MSMI':
      PIN_NUMBER='(0,0,0,0,Y4,0,0,0,0,0,0)';
      BIDIRECTIONAL='TRUE';
      INPUT_LOAD='(-0.01,0.01)';
      OUTPUT_LOAD='(1.0,-1.0)';
    'GPP_D_1_HS_SMBDATA_DMA_SMBDATA':
      PIN_NUMBER='(0,0,0,0,AE1,0,0,0,0,0,0)';
      BIDIRECTIONAL='TRUE';
      INPUT_LOAD='(-0.01,0.01)';
      OUTPUT_LOAD='(1.0,-1.0)';
    '-GPP_D_20_CATERR':
      PIN_NUMBER='(0,0,0,0,AG3,0,0,0,0,0,0)';
      BIDIRECTIONAL='TRUE';
      INPUT_LOAD='(-0.01,0.01)';
      OUTPUT_LOAD='(1.0,-1.0)';
    '-GPP_D_21_GLB_RST_WARN':
      PIN_NUMBER='(0,0,0,0,AA1,0,0,0,0,0,0)';
      BIDIRECTIONAL='TRUE';
      INPUT_LOAD='(-0.01,0.01)';
      OUTPUT_LOAD='(1.0,-1.0)';
    'GPP_D_22_USB2_OCB_7':
      PIN_NUMBER='(0,0,0,0,AA3,0,0,0,0,0,0)';
      BIDIRECTIONAL='TRUE';
      INPUT_LOAD='(-0.01,0.01)';
      OUTPUT_LOAD='(1.0,-1.0)';
    'GPP_D_23':
      PIN_NUMBER='(0,0,0,0,W1,0,0,0,0,0,0)';
      BIDIRECTIONAL='TRUE';
      INPUT_LOAD='(-0.01,0.01)';
      OUTPUT_LOAD='(1.0,-1.0)';
    '-GPP_D_2_HS_SMBALERT_N_DMA_SMBALERT':
      PIN_NUMBER='(0,0,0,0,AD2,0,0,0,0,0,0)';
      BIDIRECTIONAL='TRUE';
      INPUT_LOAD='(-0.01,0.01)';
      OUTPUT_LOAD='(1.0,-1.0)';
    'GPP_D_6':
      PIN_NUMBER='(0,0,0,0,AJ1,0,0,0,0,0,0)';
      BIDIRECTIONAL='TRUE';
      INPUT_LOAD='(-0.01,0.01)';
      OUTPUT_LOAD='(1.0,-1.0)';
    'GPP_D_7':
      PIN_NUMBER='(0,0,0,0,AG1,0,0,0,0,0,0)';
      BIDIRECTIONAL='TRUE';
      INPUT_LOAD='(-0.01,0.01)';
      OUTPUT_LOAD='(1.0,-1.0)';
    '-GPP_D_8_CRASHLOG_TRIG':
      PIN_NUMBER='(0,0,0,0,AE3,0,0,0,0,0,0)';
      BIDIRECTIONAL='TRUE';
      INPUT_LOAD='(-0.01,0.01)';
      OUTPUT_LOAD='(1.0,-1.0)';
    '-GPP_D_9_PME':
      PIN_NUMBER='(0,0,0,0,AJ3,0,0,0,0,0,0)';
      BIDIRECTIONAL='TRUE';
      INPUT_LOAD='(-0.01,0.01)';
      OUTPUT_LOAD='(1.0,-1.0)';
    'GPPC_H_0':
      PIN_NUMBER='(0,0,0,0,0,G4,0,0,0,0,0)';
      BIDIRECTIONAL='TRUE';
      INPUT_LOAD='(-0.01,0.01)';
      OUTPUT_LOAD='(1.0,-1.0)';
    'GPPC_H_1':
      PIN_NUMBER='(0,0,0,0,0,K1,0,0,0,0,0)';
      BIDIRECTIONAL='TRUE';
      INPUT_LOAD='(-0.01,0.01)';
      OUTPUT_LOAD='(1.0,-1.0)';
    'GPPC_H_15_FLEX_CLK_OUT_0':
      PIN_NUMBER='(0,0,0,0,0,J2,0,0,0,0,0)';
      BIDIRECTIONAL='TRUE';
      INPUT_LOAD='(-0.01,0.01)';
      OUTPUT_LOAD='(1.0,-1.0)';
    'GPPC_H_16_FLEX_CLK_OUT_1':
      PIN_NUMBER='(0,0,0,0,0,G2,0,0,0,0,0)';
      BIDIRECTIONAL='TRUE';
      INPUT_LOAD='(-0.01,0.01)';
      OUTPUT_LOAD='(1.0,-1.0)';
    'GPPC_H_17_FLEX_CLK_OUT_2':
      PIN_NUMBER='(0,0,0,0,0,H3,0,0,0,0,0)';
      BIDIRECTIONAL='TRUE';
      INPUT_LOAD='(-0.01,0.01)';
      OUTPUT_LOAD='(1.0,-1.0)';
    '-GPPC_H_18_PMCALERT':
      PIN_NUMBER='(0,0,0,0,0,J4,0,0,0,0,0)';
      BIDIRECTIONAL='TRUE';
      INPUT_LOAD='(-0.01,0.01)';
      OUTPUT_LOAD='(1.0,-1.0)';
    'GPPC_H_19':
      PIN_NUMBER='(0,0,0,0,0,L4,0,0,0,0,0)';
      BIDIRECTIONAL='TRUE';
      INPUT_LOAD='(-0.01,0.01)';
      OUTPUT_LOAD='(1.0,-1.0)';
    'GPPC_H_6':
      PIN_NUMBER='(0,0,0,0,0,L2,0,0,0,0,0)';
      BIDIRECTIONAL='TRUE';
      INPUT_LOAD='(-0.01,0.01)';
      OUTPUT_LOAD='(1.0,-1.0)';
    'GPPC_H_7':
      PIN_NUMBER='(0,0,0,0,0,K3,0,0,0,0,0)';
      BIDIRECTIONAL='TRUE';
      INPUT_LOAD='(-0.01,0.01)';
      OUTPUT_LOAD='(1.0,-1.0)';
    'GPP_E_0_SATA1_XPCIE_0':
      PIN_NUMBER='(0,0,0,0,0,BA26,0,0,0,0,0)';
      BIDIRECTIONAL='TRUE';
      INPUT_LOAD='(-0.01,0.01)';
      OUTPUT_LOAD='(1.0,-1.0)';
    'GPP_E_10_SATA0_SDATAOUT_SATA0_GP':
      PIN_NUMBER='(0,0,0,0,0,AV31,0,0,0,0,0)';
      BIDIRECTIONAL='TRUE';
      INPUT_LOAD='(-0.01,0.01)';
      OUTPUT_LOAD='(1.0,-1.0)';
    '-GPP_E_11_SATA1_SCLOCK_SATA1_LED':
      PIN_NUMBER='(0,0,0,0,0,AV34,0,0,0,0,0)';
      BIDIRECTIONAL='TRUE';
      INPUT_LOAD='(-0.01,0.01)';
      OUTPUT_LOAD='(1.0,-1.0)';
    'GPP_E_12_SATA1_SLOAD_SATA1_GP':
      PIN_NUMBER='(0,0,0,0,0,BB28,0,0,0,0,0)';
      BIDIRECTIONAL='TRUE';
      INPUT_LOAD='(-0.01,0.01)';
      OUTPUT_LOAD='(1.0,-1.0)';
    'GPP_E_13_SATA1_SDATAOUT_SATA1_DEVSLP':
      PIN_NUMBER='(0,0,0,0,0,BA32,0,0,0,0,0)';
      BIDIRECTIONAL='TRUE';
      INPUT_LOAD='(-0.01,0.01)';
      OUTPUT_LOAD='(1.0,-1.0)';
    '-GPP_E_14_SATA2_SCLOCK_SATA2_LED':
      PIN_NUMBER='(0,0,0,0,0,BB34,0,0,0,0,0)';
      BIDIRECTIONAL='TRUE';
      INPUT_LOAD='(-0.01,0.01)';
      OUTPUT_LOAD='(1.0,-1.0)';
    'GPP_E_15_SATA2_SLOAD_SATA2_GP':
      PIN_NUMBER='(0,0,0,0,0,AW20,0,0,0,0,0)';
      BIDIRECTIONAL='TRUE';
      INPUT_LOAD='(-0.01,0.01)';
      OUTPUT_LOAD='(1.0,-1.0)';
    'GPP_E_16_SATA2_SDATAOUT_SATA2_DEVSLP':
      PIN_NUMBER='(0,0,0,0,0,AW29,0,0,0,0,0)';
      BIDIRECTIONAL='TRUE';
      INPUT_LOAD='(-0.01,0.01)';
      OUTPUT_LOAD='(1.0,-1.0)';
    '-GPP_E_17_ERR0':
      PIN_NUMBER='(0,0,0,0,0,BA36,0,0,0,0,0)';
      BIDIRECTIONAL='TRUE';
      INPUT_LOAD='(-0.01,0.01)';
      OUTPUT_LOAD='(1.0,-1.0)';
    '-GPP_E_18_ERR1':
      PIN_NUMBER='(0,0,0,0,0,BA20,0,0,0,0,0)';
      BIDIRECTIONAL='TRUE';
      INPUT_LOAD='(-0.01,0.01)';
      OUTPUT_LOAD='(1.0,-1.0)';
    '-GPP_E_19_ERR2':
      PIN_NUMBER='(0,0,0,0,0,BB31,0,0,0,0,0)';
      BIDIRECTIONAL='TRUE';
      INPUT_LOAD='(-0.01,0.01)';
      OUTPUT_LOAD='(1.0,-1.0)';
    'GPP_E_1_SATA1_XPCIE_1':
      PIN_NUMBER='(0,0,0,0,0,BA23,0,0,0,0,0)';
      BIDIRECTIONAL='TRUE';
      INPUT_LOAD='(-0.01,0.01)';
      OUTPUT_LOAD='(1.0,-1.0)';
    'GPP_E_2_SATA1_XPCIE_2':
      PIN_NUMBER='(0,0,0,0,0,AW23,0,0,0,0,0)';
      BIDIRECTIONAL='TRUE';
      INPUT_LOAD='(-0.01,0.01)';
      OUTPUT_LOAD='(1.0,-1.0)';
    'GPP_E_3_SATA1_XPCIE_3':
      PIN_NUMBER='(0,0,0,0,0,BB21,0,0,0,0,0)';
      BIDIRECTIONAL='TRUE';
      INPUT_LOAD='(-0.01,0.01)';
      OUTPUT_LOAD='(1.0,-1.0)';
    'GPP_E_4_SATA0_XPCIE_2':
      PIN_NUMBER='(0,0,0,0,0,AV24,0,0,0,0,0)';
      BIDIRECTIONAL='TRUE';
      INPUT_LOAD='(-0.01,0.01)';
      OUTPUT_LOAD='(1.0,-1.0)';
    'GPP_E_5_SATA0_XPCIE_3':
      PIN_NUMBER='(0,0,0,0,0,AV28,0,0,0,0,0)';
      BIDIRECTIONAL='TRUE';
      INPUT_LOAD='(-0.01,0.01)';
      OUTPUT_LOAD='(1.0,-1.0)';
    'GPP_E_6_SATA0_USB3_XPCIE_0':
      PIN_NUMBER='(0,0,0,0,0,BB24,0,0,0,0,0)';
      BIDIRECTIONAL='TRUE';
      INPUT_LOAD='(-0.01,0.01)';
      OUTPUT_LOAD='(1.0,-1.0)';
    'GPP_E_7_SATA0_USB3_XPCIE_1':
      PIN_NUMBER='(0,0,0,0,0,AW32,0,0,0,0,0)';
      BIDIRECTIONAL='TRUE';
      INPUT_LOAD='(-0.01,0.01)';
      OUTPUT_LOAD='(1.0,-1.0)';
    '-GPP_E_8_SATA0_SCLOCK_SATA0_LED':
      PIN_NUMBER='(0,0,0,0,0,AW36,0,0,0,0,0)';
      BIDIRECTIONAL='TRUE';
      INPUT_LOAD='(-0.01,0.01)';
      OUTPUT_LOAD='(1.0,-1.0)';
    'GPP_E_9_SATA0_SLOAD_SATA0_DEVSLP':
      PIN_NUMBER='(0,0,0,0,0,BA29,0,0,0,0,0)';
      BIDIRECTIONAL='TRUE';
      INPUT_LOAD='(-0.01,0.01)';
      OUTPUT_LOAD='(1.0,-1.0)';
    'GPP_I_12_HDA_BCLK':
      PIN_NUMBER='(0,0,0,0,0,U3,0,0,0,0,0)';
      BIDIRECTIONAL='TRUE';
      INPUT_LOAD='(-0.01,0.01)';
      OUTPUT_LOAD='(1.0,-1.0)';
    '-GPP_I_13_HDA_RST':
      PIN_NUMBER='(0,0,0,0,0,N2,0,0,0,0,0)';
      BIDIRECTIONAL='TRUE';
      INPUT_LOAD='(-0.01,0.01)';
      OUTPUT_LOAD='(1.0,-1.0)';
    'GPP_I_14_HDA_SYNC':
      PIN_NUMBER='(0,0,0,0,0,P1,0,0,0,0,0)';
      BIDIRECTIONAL='TRUE';
      INPUT_LOAD='(-0.01,0.01)';
      OUTPUT_LOAD='(1.0,-1.0)';
    'GPP_I_15_HDA_SDO':
      PIN_NUMBER='(0,0,0,0,0,R2,0,0,0,0,0)';
      BIDIRECTIONAL='TRUE';
      INPUT_LOAD='(-0.01,0.01)';
      OUTPUT_LOAD='(1.0,-1.0)';
    'GPP_I_16_HDA_SDI_0':
      PIN_NUMBER='(0,0,0,0,0,U1,0,0,0,0,0)';
      BIDIRECTIONAL='TRUE';
      INPUT_LOAD='(-0.01,0.01)';
      OUTPUT_LOAD='(1.0,-1.0)';
    'GPP_I_17_HDA_SDI_1':
      PIN_NUMBER='(0,0,0,0,0,V4,0,0,0,0,0)';
      BIDIRECTIONAL='TRUE';
      INPUT_LOAD='(-0.01,0.01)';
      OUTPUT_LOAD='(1.0,-1.0)';
    'GPP_I_21':
      PIN_NUMBER='(0,0,0,0,0,N4,0,0,0,0,0)';
      BIDIRECTIONAL='TRUE';
      INPUT_LOAD='(-0.01,0.01)';
      OUTPUT_LOAD='(1.0,-1.0)';
    'GPP_I_22':
      PIN_NUMBER='(0,0,0,0,0,P3,0,0,0,0,0)';
      BIDIRECTIONAL='TRUE';
      INPUT_LOAD='(-0.01,0.01)';
      OUTPUT_LOAD='(1.0,-1.0)';
    'GPP_I_23':
      PIN_NUMBER='(0,0,0,0,0,R4,0,0,0,0,0)';
      BIDIRECTIONAL='TRUE';
      INPUT_LOAD='(-0.01,0.01)';
      OUTPUT_LOAD='(1.0,-1.0)';
    'GPP_L_0_PM_SYNC_0':
      PIN_NUMBER='(0,0,0,0,0,AF8,0,0,0,0,0)';
      BIDIRECTIONAL='TRUE';
      INPUT_LOAD='(-0.01,0.01)';
      OUTPUT_LOAD='(1.0,-1.0)';
    'GPP_L_1_PM_DOWN_0':
      PIN_NUMBER='(0,0,0,0,0,AE7,0,0,0,0,0)';
      BIDIRECTIONAL='TRUE';
      INPUT_LOAD='(-0.01,0.01)';
      OUTPUT_LOAD='(1.0,-1.0)';
    'GPP_L_2':
      PIN_NUMBER='(0,0,0,0,0,AC10,0,0,0,0,0)';
      BIDIRECTIONAL='TRUE';
      INPUT_LOAD='(-0.01,0.01)';
      OUTPUT_LOAD='(1.0,-1.0)';
    'GPP_L_3':
      PIN_NUMBER='(0,0,0,0,0,AF11,0,0,0,0,0)';
      BIDIRECTIONAL='TRUE';
      INPUT_LOAD='(-0.01,0.01)';
      OUTPUT_LOAD='(1.0,-1.0)';
    'GPP_L_4':
      PIN_NUMBER='(0,0,0,0,0,AG7,0,0,0,0,0)';
      BIDIRECTIONAL='TRUE';
      INPUT_LOAD='(-0.01,0.01)';
      OUTPUT_LOAD='(1.0,-1.0)';
    'GPP_L_5':
      PIN_NUMBER='(0,0,0,0,0,AB8,0,0,0,0,0)';
      BIDIRECTIONAL='TRUE';
      INPUT_LOAD='(-0.01,0.01)';
      OUTPUT_LOAD='(1.0,-1.0)';
    'GPP_L_6':
      PIN_NUMBER='(0,0,0,0,0,AG10,0,0,0,0,0)';
      BIDIRECTIONAL='TRUE';
      INPUT_LOAD='(-0.01,0.01)';
      OUTPUT_LOAD='(1.0,-1.0)';
    'GPP_L_7':
      PIN_NUMBER='(0,0,0,0,0,AC7,0,0,0,0,0)';
      BIDIRECTIONAL='TRUE';
      INPUT_LOAD='(-0.01,0.01)';
      OUTPUT_LOAD='(1.0,-1.0)';
    'GPP_L_8':
      PIN_NUMBER='(0,0,0,0,0,AE10,0,0,0,0,0)';
      BIDIRECTIONAL='TRUE';
      INPUT_LOAD='(-0.01,0.01)';
      OUTPUT_LOAD='(1.0,-1.0)';
    'GPP_M_0':
      PIN_NUMBER='(0,0,0,0,0,N7,0,0,0,0,0)';
      BIDIRECTIONAL='TRUE';
      INPUT_LOAD='(-0.01,0.01)';
      OUTPUT_LOAD='(1.0,-1.0)';
    'GPP_M_1':
      PIN_NUMBER='(0,0,0,0,0,AA13,0,0,0,0,0)';
      BIDIRECTIONAL='TRUE';
      INPUT_LOAD='(-0.01,0.01)';
      OUTPUT_LOAD='(1.0,-1.0)';
    'GPP_M_11':
      PIN_NUMBER='(0,0,0,0,0,R7,0,0,0,0,0)';
      BIDIRECTIONAL='TRUE';
      INPUT_LOAD='(-0.01,0.01)';
      OUTPUT_LOAD='(1.0,-1.0)';
    'GPP_M_12':
      PIN_NUMBER='(0,0,0,0,0,U7,0,0,0,0,0)';
      BIDIRECTIONAL='TRUE';
      INPUT_LOAD='(-0.01,0.01)';
      OUTPUT_LOAD='(1.0,-1.0)';
    'GPP_M_15':
      PIN_NUMBER='(0,0,0,0,0,T8,0,0,0,0,0)';
      BIDIRECTIONAL='TRUE';
      INPUT_LOAD='(-0.01,0.01)';
      OUTPUT_LOAD='(1.0,-1.0)';
    'GPP_M_16':
      PIN_NUMBER='(0,0,0,0,0,N10,0,0,0,0,0)';
      BIDIRECTIONAL='TRUE';
      INPUT_LOAD='(-0.01,0.01)';
      OUTPUT_LOAD='(1.0,-1.0)';
    'GPP_M_17':
      PIN_NUMBER='(0,0,0,0,0,W13,0,0,0,0,0)';
      BIDIRECTIONAL='TRUE';
      INPUT_LOAD='(-0.01,0.01)';
      OUTPUT_LOAD='(1.0,-1.0)';
    'GPP_M_2':
      PIN_NUMBER='(0,0,0,0,0,AA7,0,0,0,0,0)';
      BIDIRECTIONAL='TRUE';
      INPUT_LOAD='(-0.01,0.01)';
      OUTPUT_LOAD='(1.0,-1.0)';
    'GPP_M_3':
      PIN_NUMBER='(0,0,0,0,0,AA10,0,0,0,0,0)';
      BIDIRECTIONAL='TRUE';
      INPUT_LOAD='(-0.01,0.01)';
      OUTPUT_LOAD='(1.0,-1.0)';
    'GPP_M_4':
      PIN_NUMBER='(0,0,0,0,0,W7,0,0,0,0,0)';
      BIDIRECTIONAL='TRUE';
      INPUT_LOAD='(-0.01,0.01)';
      OUTPUT_LOAD='(1.0,-1.0)';
    'GPP_M_5':
      PIN_NUMBER='(0,0,0,0,0,V8,0,0,0,0,0)';
      BIDIRECTIONAL='TRUE';
      INPUT_LOAD='(-0.01,0.01)';
      OUTPUT_LOAD='(1.0,-1.0)';
    'GPP_M_6':
      PIN_NUMBER='(0,0,0,0,0,R10,0,0,0,0,0)';
      BIDIRECTIONAL='TRUE';
      INPUT_LOAD='(-0.01,0.01)';
      OUTPUT_LOAD='(1.0,-1.0)';
    'GPP_M_7':
      PIN_NUMBER='(0,0,0,0,0,AB11,0,0,0,0,0)';
      BIDIRECTIONAL='TRUE';
      INPUT_LOAD='(-0.01,0.01)';
      OUTPUT_LOAD='(1.0,-1.0)';
    'GPP_M_8':
      PIN_NUMBER='(0,0,0,0,0,W10,0,0,0,0,0)';
      BIDIRECTIONAL='TRUE';
      INPUT_LOAD='(-0.01,0.01)';
      OUTPUT_LOAD='(1.0,-1.0)';
    'GPPC_S_0_TIME_SYNC_0':
      PIN_NUMBER='(0,0,0,0,0,0,BB18,0,0,0,0)';
      BIDIRECTIONAL='TRUE';
      INPUT_LOAD='(-0.01,0.01)';
      OUTPUT_LOAD='(1.0,-1.0)';
    'GPPC_S_10':
      PIN_NUMBER='(0,0,0,0,0,0,AW10,0,0,0,0)';
      BIDIRECTIONAL='TRUE';
      INPUT_LOAD='(-0.01,0.01)';
      OUTPUT_LOAD='(1.0,-1.0)';
    'GPPC_S_11':
      PIN_NUMBER='(0,0,0,0,0,0,BB8,0,0,0,0)';
      BIDIRECTIONAL='TRUE';
      INPUT_LOAD='(-0.01,0.01)';
      OUTPUT_LOAD='(1.0,-1.0)';
    'GPPC_S_1_SPKR_TIME_SYNC_1':
      PIN_NUMBER='(0,0,0,0,0,0,AU16,0,0,0,0)';
      BIDIRECTIONAL='TRUE';
      INPUT_LOAD='(-0.01,0.01)';
      OUTPUT_LOAD='(1.0,-1.0)';
    'GPPC_S_2_CPU_GP_0':
      PIN_NUMBER='(0,0,0,0,0,0,AR16,0,0,0,0)';
      BIDIRECTIONAL='TRUE';
      INPUT_LOAD='(-0.01,0.01)';
      OUTPUT_LOAD='(1.0,-1.0)';
    'GPPC_S_3_CPU_GP_1':
      PIN_NUMBER='(0,0,0,0,0,0,AV11,0,0,0,0)';
      BIDIRECTIONAL='TRUE';
      INPUT_LOAD='(-0.01,0.01)';
      OUTPUT_LOAD='(1.0,-1.0)';
    'GPPC_S_4_CPU_GP_2':
      PIN_NUMBER='(0,0,0,0,0,0,AU13,0,0,0,0)';
      BIDIRECTIONAL='TRUE';
      INPUT_LOAD='(-0.01,0.01)';
      OUTPUT_LOAD='(1.0,-1.0)';
    'GPPC_S_5_CPU_GP_3':
      PIN_NUMBER='(0,0,0,0,0,0,AT18,0,0,0,0)';
      BIDIRECTIONAL='TRUE';
      INPUT_LOAD='(-0.01,0.01)';
      OUTPUT_LOAD='(1.0,-1.0)';
    'GPPC_S_6_SUSWARN_N_SUSPWRDNACK':
      PIN_NUMBER='(0,0,0,0,0,0,AR13,0,0,0,0)';
      BIDIRECTIONAL='TRUE';
      INPUT_LOAD='(-0.01,0.01)';
      OUTPUT_LOAD='(1.0,-1.0)';
    '-GPPC_S_7_SUSACK':
      PIN_NUMBER='(0,0,0,0,0,0,BA7,0,0,0,0)';
      BIDIRECTIONAL='TRUE';
      INPUT_LOAD='(-0.01,0.01)';
      OUTPUT_LOAD='(1.0,-1.0)';
    '-GPPC_S_8_NMI':
      PIN_NUMBER='(0,0,0,0,0,0,AP15,0,0,0,0)';
      BIDIRECTIONAL='TRUE';
      INPUT_LOAD='(-0.01,0.01)';
      OUTPUT_LOAD='(1.0,-1.0)';
    '-GPPC_S_9_SMI':
      PIN_NUMBER='(0,0,0,0,0,0,AV18,0,0,0,0)';
      BIDIRECTIONAL='TRUE';
      INPUT_LOAD='(-0.01,0.01)';
      OUTPUT_LOAD='(1.0,-1.0)';
    'GPP_N_1':
      PIN_NUMBER='(0,0,0,0,0,0,T11,0,0,0,0)';
      BIDIRECTIONAL='TRUE';
      INPUT_LOAD='(-0.01,0.01)';
      OUTPUT_LOAD='(1.0,-1.0)';
    'GPP_N_4':
      PIN_NUMBER='(0,0,0,0,0,0,V11,0,0,0,0)';
      BIDIRECTIONAL='TRUE';
      INPUT_LOAD='(-0.01,0.01)';
      OUTPUT_LOAD='(1.0,-1.0)';
    '-NC_CGC_DUT_DETECT':
      PIN_NUMBER='(0,0,0,0,0,0,BG3,0,0,0,0)';
      OUTPUT_TYPE='(TS,TS)';
      INPUT_LOAD='(-0.01,0.01)';
      OUTPUT_LOAD='(1.0,-1.0)';
    '-RCTRST':
      PIN_NUMBER='(0,0,0,0,0,0,BD7,0,0,0,0)';
      INPUT_LOAD='(-0.01,0.01)';
    'SPI0_CLK':
      PIN_NUMBER='(0,0,0,0,0,0,BB15,0,0,0,0)';
      OUTPUT_LOAD='(1.0,-1.0)';
    '-SPI0_FLASH_0_CS':
      PIN_NUMBER='(0,0,0,0,0,0,AW13,0,0,0,0)';
      OUTPUT_LOAD='(1.0,-1.0)';
    '-SPI0_FLASH_1_CS':
      PIN_NUMBER='(0,0,0,0,0,0,BA10,0,0,0,0)';
      OUTPUT_LOAD='(1.0,-1.0)';
    'SPI0_IO_2':
      PIN_NUMBER='(0,0,0,0,0,0,AV15,0,0,0,0)';
      BIDIRECTIONAL='TRUE';
      INPUT_LOAD='(-0.01,0.01)';
      OUTPUT_LOAD='(1.0,-1.0)';
    'SPI0_IO_3':
      PIN_NUMBER='(0,0,0,0,0,0,BA16,0,0,0,0)';
      BIDIRECTIONAL='TRUE';
      INPUT_LOAD='(-0.01,0.01)';
      OUTPUT_LOAD='(1.0,-1.0)';
    'SPI0_MOSI_IO_0':
      PIN_NUMBER='(0,0,0,0,0,0,BA13,0,0,0,0)';
      BIDIRECTIONAL='TRUE';
      INPUT_LOAD='(-0.01,0.01)';
      OUTPUT_LOAD='(1.0,-1.0)';
    'SPI0_MISO_IO_1':
      PIN_NUMBER='(0,0,0,0,0,0,AW16,0,0,0,0)';
      BIDIRECTIONAL='TRUE';
      INPUT_LOAD='(-0.01,0.01)';
      OUTPUT_LOAD='(1.0,-1.0)';
    '-SPI0_TPM_CS':
      PIN_NUMBER='(0,0,0,0,0,0,BB11,0,0,0,0)';
      OUTPUT_LOAD='(1.0,-1.0)';
    '-SRTCRST':
      PIN_NUMBER='(0,0,0,0,0,0,BF9,0,0,0,0)';
      INPUT_LOAD='(-0.01,0.01)';
    'VSS_A41':
      PIN_NUMBER='(0,0,0,0,0,0,A41,0,0,0,0)';
      PINUSE='POWER';
      NO_LOAD_CHECK='Both';
      NO_IO_CHECK='Both';
      NO_ASSERT_CHECK='TRUE';
      NO_DIR_CHECK='TRUE';
      ALLOW_CONNECT='TRUE';
    'RSVD_AF15':
      PIN_NUMBER='(0,0,0,0,0,0,0,AF15,0,0,0)';
      OUTPUT_TYPE='(TS,TS)';
      INPUT_LOAD='(-0.01,0.01)';
      OUTPUT_LOAD='(1.0,-1.0)';
    'RSVD_AN26':
      PIN_NUMBER='(0,0,0,0,0,0,0,AN26,0,0,0)';
      OUTPUT_TYPE='(TS,TS)';
      INPUT_LOAD='(-0.01,0.01)';
      OUTPUT_LOAD='(1.0,-1.0)';
    'VCCP_1P05_W24':
      PIN_NUMBER='(0,0,0,0,0,0,0,W24,0,0,0)';
      PINUSE='POWER';
      NO_LOAD_CHECK='Both';
      NO_IO_CHECK='Both';
      NO_ASSERT_CHECK='TRUE';
      NO_DIR_CHECK='TRUE';
      ALLOW_CONNECT='TRUE';
    'VCCP_1P05_W22':
      PIN_NUMBER='(0,0,0,0,0,0,0,W22,0,0,0)';
      PINUSE='POWER';
      NO_LOAD_CHECK='Both';
      NO_IO_CHECK='Both';
      NO_ASSERT_CHECK='TRUE';
      NO_DIR_CHECK='TRUE';
      ALLOW_CONNECT='TRUE';
    'VCCP_1P05_W20':
      PIN_NUMBER='(0,0,0,0,0,0,0,W20,0,0,0)';
      PINUSE='POWER';
      NO_LOAD_CHECK='Both';
      NO_IO_CHECK='Both';
      NO_ASSERT_CHECK='TRUE';
      NO_DIR_CHECK='TRUE';
      ALLOW_CONNECT='TRUE';
    'VCCP_1P05_W19':
      PIN_NUMBER='(0,0,0,0,0,0,0,W19,0,0,0)';
      PINUSE='POWER';
      NO_LOAD_CHECK='Both';
      NO_IO_CHECK='Both';
      NO_ASSERT_CHECK='TRUE';
      NO_DIR_CHECK='TRUE';
      ALLOW_CONNECT='TRUE';
    'VCCP_1P05_W17':
      PIN_NUMBER='(0,0,0,0,0,0,0,W17,0,0,0)';
      PINUSE='POWER';
      NO_LOAD_CHECK='Both';
      NO_IO_CHECK='Both';
      NO_ASSERT_CHECK='TRUE';
      NO_DIR_CHECK='TRUE';
      ALLOW_CONNECT='TRUE';
    'VCCP_1P05_AB24':
      PIN_NUMBER='(0,0,0,0,0,0,0,AB24,0,0,0)';
      PINUSE='POWER';
      NO_LOAD_CHECK='Both';
      NO_IO_CHECK='Both';
      NO_ASSERT_CHECK='TRUE';
      NO_DIR_CHECK='TRUE';
      ALLOW_CONNECT='TRUE';
    'VCCP_1P05_AB22':
      PIN_NUMBER='(0,0,0,0,0,0,0,AB22,0,0,0)';
      PINUSE='POWER';
      NO_LOAD_CHECK='Both';
      NO_IO_CHECK='Both';
      NO_ASSERT_CHECK='TRUE';
      NO_DIR_CHECK='TRUE';
      ALLOW_CONNECT='TRUE';
    'VCCP_1P05_AB20':
      PIN_NUMBER='(0,0,0,0,0,0,0,AB20,0,0,0)';
      PINUSE='POWER';
      NO_LOAD_CHECK='Both';
      NO_IO_CHECK='Both';
      NO_ASSERT_CHECK='TRUE';
      NO_DIR_CHECK='TRUE';
      ALLOW_CONNECT='TRUE';
    'VCCP_1P05_AB19':
      PIN_NUMBER='(0,0,0,0,0,0,0,AB19,0,0,0)';
      PINUSE='POWER';
      NO_LOAD_CHECK='Both';
      NO_IO_CHECK='Both';
      NO_ASSERT_CHECK='TRUE';
      NO_DIR_CHECK='TRUE';
      ALLOW_CONNECT='TRUE';
    'VCCP_1P05_AJ27':
      PIN_NUMBER='(0,0,0,0,0,0,0,AJ27,0,0,0)';
      PINUSE='POWER';
      NO_LOAD_CHECK='Both';
      NO_IO_CHECK='Both';
      NO_ASSERT_CHECK='TRUE';
      NO_DIR_CHECK='TRUE';
      ALLOW_CONNECT='TRUE';
    'VCCP_1P05_AJ25':
      PIN_NUMBER='(0,0,0,0,0,0,0,AJ25,0,0,0)';
      PINUSE='POWER';
      NO_LOAD_CHECK='Both';
      NO_IO_CHECK='Both';
      NO_ASSERT_CHECK='TRUE';
      NO_DIR_CHECK='TRUE';
      ALLOW_CONNECT='TRUE';
    'VCCP_1P05_AG27':
      PIN_NUMBER='(0,0,0,0,0,0,0,AG27,0,0,0)';
      PINUSE='POWER';
      NO_LOAD_CHECK='Both';
      NO_IO_CHECK='Both';
      NO_ASSERT_CHECK='TRUE';
      NO_DIR_CHECK='TRUE';
      ALLOW_CONNECT='TRUE';
    'VCCP_1P05_AG25':
      PIN_NUMBER='(0,0,0,0,0,0,0,AG25,0,0,0)';
      PINUSE='POWER';
      NO_LOAD_CHECK='Both';
      NO_IO_CHECK='Both';
      NO_ASSERT_CHECK='TRUE';
      NO_DIR_CHECK='TRUE';
      ALLOW_CONNECT='TRUE';
    'VCCP_1P05_AF27':
      PIN_NUMBER='(0,0,0,0,0,0,0,AF27,0,0,0)';
      PINUSE='POWER';
      NO_LOAD_CHECK='Both';
      NO_IO_CHECK='Both';
      NO_ASSERT_CHECK='TRUE';
      NO_DIR_CHECK='TRUE';
      ALLOW_CONNECT='TRUE';
    'VCCP_1P05_AF25':
      PIN_NUMBER='(0,0,0,0,0,0,0,AF25,0,0,0)';
      PINUSE='POWER';
      NO_LOAD_CHECK='Both';
      NO_IO_CHECK='Both';
      NO_ASSERT_CHECK='TRUE';
      NO_DIR_CHECK='TRUE';
      ALLOW_CONNECT='TRUE';
    'VCCP_1P05_AD27':
      PIN_NUMBER='(0,0,0,0,0,0,0,AD27,0,0,0)';
      PINUSE='POWER';
      NO_LOAD_CHECK='Both';
      NO_IO_CHECK='Both';
      NO_ASSERT_CHECK='TRUE';
      NO_DIR_CHECK='TRUE';
      ALLOW_CONNECT='TRUE';
    'VCCP_1P05_AD25':
      PIN_NUMBER='(0,0,0,0,0,0,0,AD25,0,0,0)';
      PINUSE='POWER';
      NO_LOAD_CHECK='Both';
      NO_IO_CHECK='Both';
      NO_ASSERT_CHECK='TRUE';
      NO_DIR_CHECK='TRUE';
      ALLOW_CONNECT='TRUE';
    'VCCP_1P05_FILTERED_AB27':
      PIN_NUMBER='(0,0,0,0,0,0,0,AB27,0,0,0)';
      PINUSE='POWER';
      NO_LOAD_CHECK='Both';
      NO_IO_CHECK='Both';
      NO_ASSERT_CHECK='TRUE';
      NO_DIR_CHECK='TRUE';
      ALLOW_CONNECT='TRUE';
    'VCCP_1P05_N26':
      PIN_NUMBER='(0,0,0,0,0,0,0,N26,0,0,0)';
      PINUSE='POWER';
      NO_LOAD_CHECK='Both';
      NO_IO_CHECK='Both';
      NO_ASSERT_CHECK='TRUE';
      NO_DIR_CHECK='TRUE';
      ALLOW_CONNECT='TRUE';
    'VCCP_1P05_N23':
      PIN_NUMBER='(0,0,0,0,0,0,0,N23,0,0,0)';
      PINUSE='POWER';
      NO_LOAD_CHECK='Both';
      NO_IO_CHECK='Both';
      NO_ASSERT_CHECK='TRUE';
      NO_DIR_CHECK='TRUE';
      ALLOW_CONNECT='TRUE';
    'VCCP_1P05_AR26':
      PIN_NUMBER='(0,0,0,0,0,0,0,AR26,0,0,0)';
      PINUSE='POWER';
      NO_LOAD_CHECK='Both';
      NO_IO_CHECK='Both';
      NO_ASSERT_CHECK='TRUE';
      NO_DIR_CHECK='TRUE';
      ALLOW_CONNECT='TRUE';
    'VCCP_1P05_M24':
      PIN_NUMBER='(0,0,0,0,0,0,0,M24,0,0,0)';
      PINUSE='POWER';
      NO_LOAD_CHECK='Both';
      NO_IO_CHECK='Both';
      NO_ASSERT_CHECK='TRUE';
      NO_DIR_CHECK='TRUE';
      ALLOW_CONNECT='TRUE';
    'VCCP_1P05_P15':
      PIN_NUMBER='(0,0,0,0,0,0,0,P15,0,0,0)';
      PINUSE='POWER';
      NO_LOAD_CHECK='Both';
      NO_IO_CHECK='Both';
      NO_ASSERT_CHECK='TRUE';
      NO_DIR_CHECK='TRUE';
      ALLOW_CONNECT='TRUE';
    'VCCP_1P05_FILTERED_AL25':
      PIN_NUMBER='(0,0,0,0,0,0,0,AL25,0,0,0)';
      PINUSE='POWER';
      NO_LOAD_CHECK='Both';
      NO_IO_CHECK='Both';
      NO_ASSERT_CHECK='TRUE';
      NO_DIR_CHECK='TRUE';
      ALLOW_CONNECT='TRUE';
    'VCCP_1P05_FILTERED_AG29':
      PIN_NUMBER='(0,0,0,0,0,0,0,AG29,0,0,0)';
      PINUSE='POWER';
      NO_LOAD_CHECK='Both';
      NO_IO_CHECK='Both';
      NO_ASSERT_CHECK='TRUE';
      NO_DIR_CHECK='TRUE';
      ALLOW_CONNECT='TRUE';
    'VCCP_1P05_FILTERED_AE29':
      PIN_NUMBER='(0,0,0,0,0,0,0,AE29,0,0,0)';
      PINUSE='POWER';
      NO_LOAD_CHECK='Both';
      NO_IO_CHECK='Both';
      NO_ASSERT_CHECK='TRUE';
      NO_DIR_CHECK='TRUE';
      ALLOW_CONNECT='TRUE';
    'VCCP_1P05_FILTERED_R29':
      PIN_NUMBER='(0,0,0,0,0,0,0,R29,0,0,0)';
      PINUSE='POWER';
      NO_LOAD_CHECK='Both';
      NO_IO_CHECK='Both';
      NO_ASSERT_CHECK='TRUE';
      NO_DIR_CHECK='TRUE';
      ALLOW_CONNECT='TRUE';
    'VCCP_1P05_FILTERED_U27':
      PIN_NUMBER='(0,0,0,0,0,0,0,U27,0,0,0)';
      PINUSE='POWER';
      NO_LOAD_CHECK='Both';
      NO_IO_CHECK='Both';
      NO_ASSERT_CHECK='TRUE';
      NO_DIR_CHECK='TRUE';
      ALLOW_CONNECT='TRUE';
    'VCCP_1P05_FILTERED_AA29':
      PIN_NUMBER='(0,0,0,0,0,0,0,AA29,0,0,0)';
      PINUSE='POWER';
      NO_LOAD_CHECK='Both';
      NO_IO_CHECK='Both';
      NO_ASSERT_CHECK='TRUE';
      NO_DIR_CHECK='TRUE';
      ALLOW_CONNECT='TRUE';
    'VCCP_1P05_FILTERED_R26':
      PIN_NUMBER='(0,0,0,0,0,0,0,R26,0,0,0)';
      PINUSE='POWER';
      NO_LOAD_CHECK='Both';
      NO_IO_CHECK='Both';
      NO_ASSERT_CHECK='TRUE';
      NO_DIR_CHECK='TRUE';
      ALLOW_CONNECT='TRUE';
    'VCCP_1P05_FILTERED_R23':
      PIN_NUMBER='(0,0,0,0,0,0,0,R23,0,0,0)';
      PINUSE='POWER';
      NO_LOAD_CHECK='Both';
      NO_IO_CHECK='Both';
      NO_ASSERT_CHECK='TRUE';
      NO_DIR_CHECK='TRUE';
      ALLOW_CONNECT='TRUE';
    'VCCP_1P8_N20':
      PIN_NUMBER='(0,0,0,0,0,0,0,N20,0,0,0)';
      PINUSE='POWER';
      NO_LOAD_CHECK='Both';
      NO_IO_CHECK='Both';
      NO_ASSERT_CHECK='TRUE';
      NO_DIR_CHECK='TRUE';
      ALLOW_CONNECT='TRUE';
    'VCCP_1P8_U24':
      PIN_NUMBER='(0,0,0,0,0,0,0,U24,0,0,0)';
      PINUSE='POWER';
      NO_LOAD_CHECK='Both';
      NO_IO_CHECK='Both';
      NO_ASSERT_CHECK='TRUE';
      NO_DIR_CHECK='TRUE';
      ALLOW_CONNECT='TRUE';
    'VCCP_1P8_U22':
      PIN_NUMBER='(0,0,0,0,0,0,0,U22,0,0,0)';
      PINUSE='POWER';
      NO_LOAD_CHECK='Both';
      NO_IO_CHECK='Both';
      NO_ASSERT_CHECK='TRUE';
      NO_DIR_CHECK='TRUE';
      ALLOW_CONNECT='TRUE';
    'VCCP_1P8_U20':
      PIN_NUMBER='(0,0,0,0,0,0,0,U20,0,0,0)';
      PINUSE='POWER';
      NO_LOAD_CHECK='Both';
      NO_IO_CHECK='Both';
      NO_ASSERT_CHECK='TRUE';
      NO_DIR_CHECK='TRUE';
      ALLOW_CONNECT='TRUE';
    'VCCP_1P8_U19':
      PIN_NUMBER='(0,0,0,0,0,0,0,U19,0,0,0)';
      PINUSE='POWER';
      NO_LOAD_CHECK='Both';
      NO_IO_CHECK='Both';
      NO_ASSERT_CHECK='TRUE';
      NO_DIR_CHECK='TRUE';
      ALLOW_CONNECT='TRUE';
    'VCCP_1P8_U17':
      PIN_NUMBER='(0,0,0,0,0,0,0,U17,0,0,0)';
      PINUSE='POWER';
      NO_LOAD_CHECK='Both';
      NO_IO_CHECK='Both';
      NO_ASSERT_CHECK='TRUE';
      NO_DIR_CHECK='TRUE';
      ALLOW_CONNECT='TRUE';
    'VCCP_1P8_FILTERED_AB34':
      PIN_NUMBER='(0,0,0,0,0,0,0,AB34,0,0,0)';
      PINUSE='POWER';
      NO_LOAD_CHECK='Both';
      NO_IO_CHECK='Both';
      NO_ASSERT_CHECK='TRUE';
      NO_DIR_CHECK='TRUE';
      ALLOW_CONNECT='TRUE';
    'VCCP_1P8_FILTERED_W29':
      PIN_NUMBER='(0,0,0,0,0,0,0,W29,0,0,0)';
      PINUSE='POWER';
      NO_LOAD_CHECK='Both';
      NO_IO_CHECK='Both';
      NO_ASSERT_CHECK='TRUE';
      NO_DIR_CHECK='TRUE';
      ALLOW_CONNECT='TRUE';
    'VCCP_1P8_FILTERED_U29':
      PIN_NUMBER='(0,0,0,0,0,0,0,U29,0,0,0)';
      PINUSE='POWER';
      NO_LOAD_CHECK='Both';
      NO_IO_CHECK='Both';
      NO_ASSERT_CHECK='TRUE';
      NO_DIR_CHECK='TRUE';
      ALLOW_CONNECT='TRUE';
    'VCCP_1P8_FILTERED_W27':
      PIN_NUMBER='(0,0,0,0,0,0,0,W27,0,0,0)';
      PINUSE='POWER';
      NO_LOAD_CHECK='Both';
      NO_IO_CHECK='Both';
      NO_ASSERT_CHECK='TRUE';
      NO_DIR_CHECK='TRUE';
      ALLOW_CONNECT='TRUE';
    'VCCP_1P8_FILTERED_AB31':
      PIN_NUMBER='(0,0,0,0,0,0,0,AB31,0,0,0)';
      PINUSE='POWER';
      NO_LOAD_CHECK='Both';
      NO_IO_CHECK='Both';
      NO_ASSERT_CHECK='TRUE';
      NO_DIR_CHECK='TRUE';
      ALLOW_CONNECT='TRUE';
    'VCCP_3P3_P21':
      PIN_NUMBER='(0,0,0,0,0,0,0,P21,0,0,0)';
      PINUSE='POWER';
      NO_LOAD_CHECK='Both';
      NO_IO_CHECK='Both';
      NO_ASSERT_CHECK='TRUE';
      NO_DIR_CHECK='TRUE';
      ALLOW_CONNECT='TRUE';
    'VCCP_3P3_AL17':
      PIN_NUMBER='(0,0,0,0,0,0,0,AL17,0,0,0)';
      PINUSE='POWER';
      NO_LOAD_CHECK='Both';
      NO_IO_CHECK='Both';
      NO_ASSERT_CHECK='TRUE';
      NO_DIR_CHECK='TRUE';
      ALLOW_CONNECT='TRUE';
    'VCCP_3P3_AJ17':
      PIN_NUMBER='(0,0,0,0,0,0,0,AJ17,0,0,0)';
      PINUSE='POWER';
      NO_LOAD_CHECK='Both';
      NO_IO_CHECK='Both';
      NO_ASSERT_CHECK='TRUE';
      NO_DIR_CHECK='TRUE';
      ALLOW_CONNECT='TRUE';
    'VCCP_3P3_AG17':
      PIN_NUMBER='(0,0,0,0,0,0,0,AG17,0,0,0)';
      PINUSE='POWER';
      NO_LOAD_CHECK='Both';
      NO_IO_CHECK='Both';
      NO_ASSERT_CHECK='TRUE';
      NO_DIR_CHECK='TRUE';
      ALLOW_CONNECT='TRUE';
    'VCCP_3P3_AF17':
      PIN_NUMBER='(0,0,0,0,0,0,0,AF17,0,0,0)';
      PINUSE='POWER';
      NO_LOAD_CHECK='Both';
      NO_IO_CHECK='Both';
      NO_ASSERT_CHECK='TRUE';
      NO_DIR_CHECK='TRUE';
      ALLOW_CONNECT='TRUE';
    'VCCP_3P3_AK15':
      PIN_NUMBER='(0,0,0,0,0,0,0,AK15,0,0,0)';
      PINUSE='POWER';
      NO_LOAD_CHECK='Both';
      NO_IO_CHECK='Both';
      NO_ASSERT_CHECK='TRUE';
      NO_DIR_CHECK='TRUE';
      ALLOW_CONNECT='TRUE';
    'VCCP_3P3_DSW_AD15':
      PIN_NUMBER='(0,0,0,0,0,0,0,AD15,0,0,0)';
      PINUSE='POWER';
      NO_LOAD_CHECK='Both';
      NO_IO_CHECK='Both';
      NO_ASSERT_CHECK='TRUE';
      NO_DIR_CHECK='TRUE';
      ALLOW_CONNECT='TRUE';
    'VCCP_3P3_DSW_V15':
      PIN_NUMBER='(0,0,0,0,0,0,0,V15,0,0,0)';
      PINUSE='POWER';
      NO_LOAD_CHECK='Both';
      NO_IO_CHECK='Both';
      NO_ASSERT_CHECK='TRUE';
      NO_DIR_CHECK='TRUE';
      ALLOW_CONNECT='TRUE';
    'VCCP_GPPD_1P8_3P3':
      PIN_NUMBER='(0,0,0,0,0,0,0,T15,0,0,0)';
      PINUSE='POWER';
      NO_LOAD_CHECK='Both';
      NO_IO_CHECK='Both';
      NO_ASSERT_CHECK='TRUE';
      NO_DIR_CHECK='TRUE';
      ALLOW_CONNECT='TRUE';
    'VCCP_GPPE_1P8_3P3':
      PIN_NUMBER='(0,0,0,0,0,0,0,AN20,0,0,0)';
      PINUSE='POWER';
      NO_LOAD_CHECK='Both';
      NO_IO_CHECK='Both';
      NO_ASSERT_CHECK='TRUE';
      NO_DIR_CHECK='TRUE';
      ALLOW_CONNECT='TRUE';
    'VCCP_GPPI_1P8_3P3':
      PIN_NUMBER='(0,0,0,0,0,0,0,AD17,0,0,0)';
      PINUSE='POWER';
      NO_LOAD_CHECK='Both';
      NO_IO_CHECK='Both';
      NO_ASSERT_CHECK='TRUE';
      NO_DIR_CHECK='TRUE';
      ALLOW_CONNECT='TRUE';
    'VCCP_VNN_AR23':
      PIN_NUMBER='(0,0,0,0,0,0,0,AR23,0,0,0)';
      PINUSE='POWER';
      NO_LOAD_CHECK='Both';
      NO_IO_CHECK='Both';
      NO_ASSERT_CHECK='TRUE';
      NO_DIR_CHECK='TRUE';
      ALLOW_CONNECT='TRUE';
    'VCCP_VNN_AP21':
      PIN_NUMBER='(0,0,0,0,0,0,0,AP21,0,0,0)';
      PINUSE='POWER';
      NO_LOAD_CHECK='Both';
      NO_IO_CHECK='Both';
      NO_ASSERT_CHECK='TRUE';
      NO_DIR_CHECK='TRUE';
      ALLOW_CONNECT='TRUE';
    'VCCP_VNN_AN23':
      PIN_NUMBER='(0,0,0,0,0,0,0,AN23,0,0,0)';
      PINUSE='POWER';
      NO_LOAD_CHECK='Both';
      NO_IO_CHECK='Both';
      NO_ASSERT_CHECK='TRUE';
      NO_DIR_CHECK='TRUE';
      ALLOW_CONNECT='TRUE';
    'VCCP_VNN_AL22':
      PIN_NUMBER='(0,0,0,0,0,0,0,AL22,0,0,0)';
      PINUSE='POWER';
      NO_LOAD_CHECK='Both';
      NO_IO_CHECK='Both';
      NO_ASSERT_CHECK='TRUE';
      NO_DIR_CHECK='TRUE';
      ALLOW_CONNECT='TRUE';
    'VCCP_VNN_AL20':
      PIN_NUMBER='(0,0,0,0,0,0,0,AL20,0,0,0)';
      PINUSE='POWER';
      NO_LOAD_CHECK='Both';
      NO_IO_CHECK='Both';
      NO_ASSERT_CHECK='TRUE';
      NO_DIR_CHECK='TRUE';
      ALLOW_CONNECT='TRUE';
    'VCCP_VNN_AJ22':
      PIN_NUMBER='(0,0,0,0,0,0,0,AJ22,0,0,0)';
      PINUSE='POWER';
      NO_LOAD_CHECK='Both';
      NO_IO_CHECK='Both';
      NO_ASSERT_CHECK='TRUE';
      NO_DIR_CHECK='TRUE';
      ALLOW_CONNECT='TRUE';
    'VCCP_VNN_AJ20':
      PIN_NUMBER='(0,0,0,0,0,0,0,AJ20,0,0,0)';
      PINUSE='POWER';
      NO_LOAD_CHECK='Both';
      NO_IO_CHECK='Both';
      NO_ASSERT_CHECK='TRUE';
      NO_DIR_CHECK='TRUE';
      ALLOW_CONNECT='TRUE';
    'VCCP_VNN_AG22':
      PIN_NUMBER='(0,0,0,0,0,0,0,AG22,0,0,0)';
      PINUSE='POWER';
      NO_LOAD_CHECK='Both';
      NO_IO_CHECK='Both';
      NO_ASSERT_CHECK='TRUE';
      NO_DIR_CHECK='TRUE';
      ALLOW_CONNECT='TRUE';
    'VCCP_VNN_AG20':
      PIN_NUMBER='(0,0,0,0,0,0,0,AG20,0,0,0)';
      PINUSE='POWER';
      NO_LOAD_CHECK='Both';
      NO_IO_CHECK='Both';
      NO_ASSERT_CHECK='TRUE';
      NO_DIR_CHECK='TRUE';
      ALLOW_CONNECT='TRUE';
    'VCCP_VNN_AF22':
      PIN_NUMBER='(0,0,0,0,0,0,0,AF22,0,0,0)';
      PINUSE='POWER';
      NO_LOAD_CHECK='Both';
      NO_IO_CHECK='Both';
      NO_ASSERT_CHECK='TRUE';
      NO_DIR_CHECK='TRUE';
      ALLOW_CONNECT='TRUE';
    'VCCP_VNN_AF20':
      PIN_NUMBER='(0,0,0,0,0,0,0,AF20,0,0,0)';
      PINUSE='POWER';
      NO_LOAD_CHECK='Both';
      NO_IO_CHECK='Both';
      NO_ASSERT_CHECK='TRUE';
      NO_DIR_CHECK='TRUE';
      ALLOW_CONNECT='TRUE';
    'VCCRTC':
      PIN_NUMBER='(0,0,0,0,0,0,0,AH15,0,0,0)';
      PINUSE='POWER';
      NO_LOAD_CHECK='Both';
      NO_IO_CHECK='Both';
      NO_ASSERT_CHECK='TRUE';
      NO_DIR_CHECK='TRUE';
      ALLOW_CONNECT='TRUE';
    'VSS_BG40':
      PIN_NUMBER='(0,0,0,0,0,0,0,BG40,0,0,0)';
      PINUSE='POWER';
      NO_LOAD_CHECK='Both';
      NO_IO_CHECK='Both';
      NO_ASSERT_CHECK='TRUE';
      NO_DIR_CHECK='TRUE';
      ALLOW_CONNECT='TRUE';
    'GPIO_RCOMP_1P8_3P3':
      PIN_NUMBER='(0,0,0,0,0,0,0,0,AC13,0,0)';
      INPUT_LOAD='(-0.01,0.01)';
    'RSVD_L13':
      PIN_NUMBER='(0,0,0,0,0,0,0,0,L13,0,0)';
      OUTPUT_TYPE='(TS,TS)';
      INPUT_LOAD='(-0.01,0.01)';
      OUTPUT_LOAD='(1.0,-1.0)';
    'RSVD_N13':
      PIN_NUMBER='(0,0,0,0,0,0,0,0,N13,0,0)';
      OUTPUT_TYPE='(TS,TS)';
      INPUT_LOAD='(-0.01,0.01)';
      OUTPUT_LOAD='(1.0,-1.0)';
    'RSVD_BB43':
      PIN_NUMBER='(0,0,0,0,0,0,0,0,BB43,0,0)';
      OUTPUT_TYPE='(TS,TS)';
      INPUT_LOAD='(-0.01,0.01)';
      OUTPUT_LOAD='(1.0,-1.0)';
    'RSVD_P18':
      PIN_NUMBER='(0,0,0,0,0,0,0,0,P18,0,0)';
      OUTPUT_TYPE='(TS,TS)';
      INPUT_LOAD='(-0.01,0.01)';
      OUTPUT_LOAD='(1.0,-1.0)';
    'RSVD_A4':
      PIN_NUMBER='(0,0,0,0,0,0,0,0,A4,0,0)';
      OUTPUT_TYPE='(TS,TS)';
      INPUT_LOAD='(-0.01,0.01)';
      OUTPUT_LOAD='(1.0,-1.0)';
    'RSVD_F1':
      PIN_NUMBER='(0,0,0,0,0,0,0,0,F1,0,0)';
      OUTPUT_TYPE='(TS,TS)';
      INPUT_LOAD='(-0.01,0.01)';
      OUTPUT_LOAD='(1.0,-1.0)';
    'RSVD_H1':
      PIN_NUMBER='(0,0,0,0,0,0,0,0,H1,0,0)';
      OUTPUT_TYPE='(TS,TS)';
      INPUT_LOAD='(-0.01,0.01)';
      OUTPUT_LOAD='(1.0,-1.0)';
    'VSS_Y8':
      PIN_NUMBER='(0,0,0,0,0,0,0,0,0,Y8,0)';
      PINUSE='POWER';
      NO_LOAD_CHECK='Both';
      NO_IO_CHECK='Both';
      NO_ASSERT_CHECK='TRUE';
      NO_DIR_CHECK='TRUE';
      ALLOW_CONNECT='TRUE';
    'VSS_Y34':
      PIN_NUMBER='(0,0,0,0,0,0,0,0,0,Y34,0)';
      PINUSE='POWER';
      NO_LOAD_CHECK='Both';
      NO_IO_CHECK='Both';
      NO_ASSERT_CHECK='TRUE';
      NO_DIR_CHECK='TRUE';
      ALLOW_CONNECT='TRUE';
    'VSS_Y31':
      PIN_NUMBER='(0,0,0,0,0,0,0,0,0,Y31,0)';
      PINUSE='POWER';
      NO_LOAD_CHECK='Both';
      NO_IO_CHECK='Both';
      NO_ASSERT_CHECK='TRUE';
      NO_DIR_CHECK='TRUE';
      ALLOW_CONNECT='TRUE';
    'VSS_Y15':
      PIN_NUMBER='(0,0,0,0,0,0,0,0,0,Y15,0)';
      PINUSE='POWER';
      NO_LOAD_CHECK='Both';
      NO_IO_CHECK='Both';
      NO_ASSERT_CHECK='TRUE';
      NO_DIR_CHECK='TRUE';
      ALLOW_CONNECT='TRUE';
    'VSS_Y11':
      PIN_NUMBER='(0,0,0,0,0,0,0,0,0,Y11,0)';
      PINUSE='POWER';
      NO_LOAD_CHECK='Both';
      NO_IO_CHECK='Both';
      NO_ASSERT_CHECK='TRUE';
      NO_DIR_CHECK='TRUE';
      ALLOW_CONNECT='TRUE';
    'VSS_W5':
      PIN_NUMBER='(0,0,0,0,0,0,0,0,0,W5,0)';
      PINUSE='POWER';
      NO_LOAD_CHECK='Both';
      NO_IO_CHECK='Both';
      NO_ASSERT_CHECK='TRUE';
      NO_DIR_CHECK='TRUE';
      ALLOW_CONNECT='TRUE';
    'VSS_W39':
      PIN_NUMBER='(0,0,0,0,0,0,0,0,0,W39,0)';
      PINUSE='POWER';
      NO_LOAD_CHECK='Both';
      NO_IO_CHECK='Both';
      NO_ASSERT_CHECK='TRUE';
      NO_DIR_CHECK='TRUE';
      ALLOW_CONNECT='TRUE';
    'VSS_W3':
      PIN_NUMBER='(0,0,0,0,0,0,0,0,0,W3,0)';
      PINUSE='POWER';
      NO_LOAD_CHECK='Both';
      NO_IO_CHECK='Both';
      NO_ASSERT_CHECK='TRUE';
      NO_DIR_CHECK='TRUE';
      ALLOW_CONNECT='TRUE';
    'VSS_W25':
      PIN_NUMBER='(0,0,0,0,0,0,0,0,0,W25,0)';
      PINUSE='POWER';
      NO_LOAD_CHECK='Both';
      NO_IO_CHECK='Both';
      NO_ASSERT_CHECK='TRUE';
      NO_DIR_CHECK='TRUE';
      ALLOW_CONNECT='TRUE';
    'VSS_V31':
      PIN_NUMBER='(0,0,0,0,0,0,0,0,0,V31,0)';
      PINUSE='POWER';
      NO_LOAD_CHECK='Both';
      NO_IO_CHECK='Both';
      NO_ASSERT_CHECK='TRUE';
      NO_DIR_CHECK='TRUE';
      ALLOW_CONNECT='TRUE';
    'VSS_V2':
      PIN_NUMBER='(0,0,0,0,0,0,0,0,0,V2,0)';
      PINUSE='POWER';
      NO_LOAD_CHECK='Both';
      NO_IO_CHECK='Both';
      NO_ASSERT_CHECK='TRUE';
      NO_DIR_CHECK='TRUE';
      ALLOW_CONNECT='TRUE';
    'VSS_U5':
      PIN_NUMBER='(0,0,0,0,0,0,0,0,0,U5,0)';
      PINUSE='POWER';
      NO_LOAD_CHECK='Both';
      NO_IO_CHECK='Both';
      NO_ASSERT_CHECK='TRUE';
      NO_DIR_CHECK='TRUE';
      ALLOW_CONNECT='TRUE';
    'VSS_U39':
      PIN_NUMBER='(0,0,0,0,0,0,0,0,0,U39,0)';
      PINUSE='POWER';
      NO_LOAD_CHECK='Both';
      NO_IO_CHECK='Both';
      NO_ASSERT_CHECK='TRUE';
      NO_DIR_CHECK='TRUE';
      ALLOW_CONNECT='TRUE';
    'VSS_U25':
      PIN_NUMBER='(0,0,0,0,0,0,0,0,0,U25,0)';
      PINUSE='POWER';
      NO_LOAD_CHECK='Both';
      NO_IO_CHECK='Both';
      NO_ASSERT_CHECK='TRUE';
      NO_DIR_CHECK='TRUE';
      ALLOW_CONNECT='TRUE';
    'VSS_U13':
      PIN_NUMBER='(0,0,0,0,0,0,0,0,0,U13,0)';
      PINUSE='POWER';
      NO_LOAD_CHECK='Both';
      NO_IO_CHECK='Both';
      NO_ASSERT_CHECK='TRUE';
      NO_DIR_CHECK='TRUE';
      ALLOW_CONNECT='TRUE';
    'VSS_U10':
      PIN_NUMBER='(0,0,0,0,0,0,0,0,0,U10,0)';
      PINUSE='POWER';
      NO_LOAD_CHECK='Both';
      NO_IO_CHECK='Both';
      NO_ASSERT_CHECK='TRUE';
      NO_DIR_CHECK='TRUE';
      ALLOW_CONNECT='TRUE';
    'VSS_T31':
      PIN_NUMBER='(0,0,0,0,0,0,0,0,0,T31,0)';
      PINUSE='POWER';
      NO_LOAD_CHECK='Both';
      NO_IO_CHECK='Both';
      NO_ASSERT_CHECK='TRUE';
      NO_DIR_CHECK='TRUE';
      ALLOW_CONNECT='TRUE';
    'VSS_R36':
      PIN_NUMBER='(0,0,0,0,0,0,0,0,0,R36,0)';
      PINUSE='POWER';
      NO_LOAD_CHECK='Both';
      NO_IO_CHECK='Both';
      NO_ASSERT_CHECK='TRUE';
      NO_DIR_CHECK='TRUE';
      ALLOW_CONNECT='TRUE';
    'VSS_R20':
      PIN_NUMBER='(0,0,0,0,0,0,0,0,0,R20,0)';
      PINUSE='POWER';
      NO_LOAD_CHECK='Both';
      NO_IO_CHECK='Both';
      NO_ASSERT_CHECK='TRUE';
      NO_DIR_CHECK='TRUE';
      ALLOW_CONNECT='TRUE';
    'VSS_R16':
      PIN_NUMBER='(0,0,0,0,0,0,0,0,0,R16,0)';
      PINUSE='POWER';
      NO_LOAD_CHECK='Both';
      NO_IO_CHECK='Both';
      NO_ASSERT_CHECK='TRUE';
      NO_DIR_CHECK='TRUE';
      ALLOW_CONNECT='TRUE';
    'VSS_R13':
      PIN_NUMBER='(0,0,0,0,0,0,0,0,0,R13,0)';
      PINUSE='POWER';
      NO_LOAD_CHECK='Both';
      NO_IO_CHECK='Both';
      NO_ASSERT_CHECK='TRUE';
      NO_DIR_CHECK='TRUE';
      ALLOW_CONNECT='TRUE';
    'VSS_P8':
      PIN_NUMBER='(0,0,0,0,0,0,0,0,0,P8,0)';
      PINUSE='POWER';
      NO_LOAD_CHECK='Both';
      NO_IO_CHECK='Both';
      NO_ASSERT_CHECK='TRUE';
      NO_DIR_CHECK='TRUE';
      ALLOW_CONNECT='TRUE';
    'VSS_P5':
      PIN_NUMBER='(0,0,0,0,0,0,0,0,0,P5,0)';
      PINUSE='POWER';
      NO_LOAD_CHECK='Both';
      NO_IO_CHECK='Both';
      NO_ASSERT_CHECK='TRUE';
      NO_DIR_CHECK='TRUE';
      ALLOW_CONNECT='TRUE';
    'VSS_P43':
      PIN_NUMBER='(0,0,0,0,0,0,0,0,0,P43,0)';
      PINUSE='POWER';
      NO_LOAD_CHECK='Both';
      NO_IO_CHECK='Both';
      NO_ASSERT_CHECK='TRUE';
      NO_DIR_CHECK='TRUE';
      ALLOW_CONNECT='TRUE';
    'VSS_P41':
      PIN_NUMBER='(0,0,0,0,0,0,0,0,0,P41,0)';
      PINUSE='POWER';
      NO_LOAD_CHECK='Both';
      NO_IO_CHECK='Both';
      NO_ASSERT_CHECK='TRUE';
      NO_DIR_CHECK='TRUE';
      ALLOW_CONNECT='TRUE';
    'VSS_P39':
      PIN_NUMBER='(0,0,0,0,0,0,0,0,0,P39,0)';
      PINUSE='POWER';
      NO_LOAD_CHECK='Both';
      NO_IO_CHECK='Both';
      NO_ASSERT_CHECK='TRUE';
      NO_DIR_CHECK='TRUE';
      ALLOW_CONNECT='TRUE';
    'VSS_P37':
      PIN_NUMBER='(0,0,0,0,0,0,0,0,0,P37,0)';
      PINUSE='POWER';
      NO_LOAD_CHECK='Both';
      NO_IO_CHECK='Both';
      NO_ASSERT_CHECK='TRUE';
      NO_DIR_CHECK='TRUE';
      ALLOW_CONNECT='TRUE';
    'VSS_P31':
      PIN_NUMBER='(0,0,0,0,0,0,0,0,0,P31,0)';
      PINUSE='POWER';
      NO_LOAD_CHECK='Both';
      NO_IO_CHECK='Both';
      NO_ASSERT_CHECK='TRUE';
      NO_DIR_CHECK='TRUE';
      ALLOW_CONNECT='TRUE';
    'VSS_P28':
      PIN_NUMBER='(0,0,0,0,0,0,0,0,0,P28,0)';
      PINUSE='POWER';
      NO_LOAD_CHECK='Both';
      NO_IO_CHECK='Both';
      NO_ASSERT_CHECK='TRUE';
      NO_DIR_CHECK='TRUE';
      ALLOW_CONNECT='TRUE';
    'VSS_P24':
      PIN_NUMBER='(0,0,0,0,0,0,0,0,0,P24,0)';
      PINUSE='POWER';
      NO_LOAD_CHECK='Both';
      NO_IO_CHECK='Both';
      NO_ASSERT_CHECK='TRUE';
      NO_DIR_CHECK='TRUE';
      ALLOW_CONNECT='TRUE';
    'VSS_P11':
      PIN_NUMBER='(0,0,0,0,0,0,0,0,0,P11,0)';
      PINUSE='POWER';
      NO_LOAD_CHECK='Both';
      NO_IO_CHECK='Both';
      NO_ASSERT_CHECK='TRUE';
      NO_DIR_CHECK='TRUE';
      ALLOW_CONNECT='TRUE';
    'VSS_N32':
      PIN_NUMBER='(0,0,0,0,0,0,0,0,0,N32,0)';
      PINUSE='POWER';
      NO_LOAD_CHECK='Both';
      NO_IO_CHECK='Both';
      NO_ASSERT_CHECK='TRUE';
      NO_DIR_CHECK='TRUE';
      ALLOW_CONNECT='TRUE';
    'VSS_N16':
      PIN_NUMBER='(0,0,0,0,0,0,0,0,0,N16,0)';
      PINUSE='POWER';
      NO_LOAD_CHECK='Both';
      NO_IO_CHECK='Both';
      NO_ASSERT_CHECK='TRUE';
      NO_DIR_CHECK='TRUE';
      ALLOW_CONNECT='TRUE';
    'VSS_M5':
      PIN_NUMBER='(0,0,0,0,0,0,0,0,0,M5,0)';
      PINUSE='POWER';
      NO_LOAD_CHECK='Both';
      NO_IO_CHECK='Both';
      NO_ASSERT_CHECK='TRUE';
      NO_DIR_CHECK='TRUE';
      ALLOW_CONNECT='TRUE';
    'VSS_M39':
      PIN_NUMBER='(0,0,0,0,0,0,0,0,0,M39,0)';
      PINUSE='POWER';
      NO_LOAD_CHECK='Both';
      NO_IO_CHECK='Both';
      NO_ASSERT_CHECK='TRUE';
      NO_DIR_CHECK='TRUE';
      ALLOW_CONNECT='TRUE';
    'VSS_M37':
      PIN_NUMBER='(0,0,0,0,0,0,0,0,0,M37,0)';
      PINUSE='POWER';
      NO_LOAD_CHECK='Both';
      NO_IO_CHECK='Both';
      NO_ASSERT_CHECK='TRUE';
      NO_DIR_CHECK='TRUE';
      ALLOW_CONNECT='TRUE';
    'VSS_M34':
      PIN_NUMBER='(0,0,0,0,0,0,0,0,0,M34,0)';
      PINUSE='POWER';
      NO_LOAD_CHECK='Both';
      NO_IO_CHECK='Both';
      NO_ASSERT_CHECK='TRUE';
      NO_DIR_CHECK='TRUE';
      ALLOW_CONNECT='TRUE';
    'VSS_M31':
      PIN_NUMBER='(0,0,0,0,0,0,0,0,0,M31,0)';
      PINUSE='POWER';
      NO_LOAD_CHECK='Both';
      NO_IO_CHECK='Both';
      NO_ASSERT_CHECK='TRUE';
      NO_DIR_CHECK='TRUE';
      ALLOW_CONNECT='TRUE';
    'VSS_M3':
      PIN_NUMBER='(0,0,0,0,0,0,0,0,0,M3,0)';
      PINUSE='POWER';
      NO_LOAD_CHECK='Both';
      NO_IO_CHECK='Both';
      NO_ASSERT_CHECK='TRUE';
      NO_DIR_CHECK='TRUE';
      ALLOW_CONNECT='TRUE';
    'VSS_M28':
      PIN_NUMBER='(0,0,0,0,0,0,0,0,0,M28,0)';
      PINUSE='POWER';
      NO_LOAD_CHECK='Both';
      NO_IO_CHECK='Both';
      NO_ASSERT_CHECK='TRUE';
      NO_DIR_CHECK='TRUE';
      ALLOW_CONNECT='TRUE';
    'VSS_M21':
      PIN_NUMBER='(0,0,0,0,0,0,0,0,0,M21,0)';
      PINUSE='POWER';
      NO_LOAD_CHECK='Both';
      NO_IO_CHECK='Both';
      NO_ASSERT_CHECK='TRUE';
      NO_DIR_CHECK='TRUE';
      ALLOW_CONNECT='TRUE';
    'VSS_M18':
      PIN_NUMBER='(0,0,0,0,0,0,0,0,0,M18,0)';
      PINUSE='POWER';
      NO_LOAD_CHECK='Both';
      NO_IO_CHECK='Both';
      NO_ASSERT_CHECK='TRUE';
      NO_DIR_CHECK='TRUE';
      ALLOW_CONNECT='TRUE';
    'VSS_M15':
      PIN_NUMBER='(0,0,0,0,0,0,0,0,0,M15,0)';
      PINUSE='POWER';
      NO_LOAD_CHECK='Both';
      NO_IO_CHECK='Both';
      NO_ASSERT_CHECK='TRUE';
      NO_DIR_CHECK='TRUE';
      ALLOW_CONNECT='TRUE';
    'VSS_M11':
      PIN_NUMBER='(0,0,0,0,0,0,0,0,0,M11,0)';
      PINUSE='POWER';
      NO_LOAD_CHECK='Both';
      NO_IO_CHECK='Both';
      NO_ASSERT_CHECK='TRUE';
      NO_DIR_CHECK='TRUE';
      ALLOW_CONNECT='TRUE';
    'VSS_M1':
      PIN_NUMBER='(0,0,0,0,0,0,0,0,0,M1,0)';
      PINUSE='POWER';
      NO_LOAD_CHECK='Both';
      NO_IO_CHECK='Both';
      NO_ASSERT_CHECK='TRUE';
      NO_DIR_CHECK='TRUE';
      ALLOW_CONNECT='TRUE';
    'VSS_L36':
      PIN_NUMBER='(0,0,0,0,0,0,0,0,0,L36,0)';
      PINUSE='POWER';
      NO_LOAD_CHECK='Both';
      NO_IO_CHECK='Both';
      NO_ASSERT_CHECK='TRUE';
      NO_DIR_CHECK='TRUE';
      ALLOW_CONNECT='TRUE';
    'VSS_L29':
      PIN_NUMBER='(0,0,0,0,0,0,0,0,0,L29,0)';
      PINUSE='POWER';
      NO_LOAD_CHECK='Both';
      NO_IO_CHECK='Both';
      NO_ASSERT_CHECK='TRUE';
      NO_DIR_CHECK='TRUE';
      ALLOW_CONNECT='TRUE';
    'VSS_L26':
      PIN_NUMBER='(0,0,0,0,0,0,0,0,0,L26,0)';
      PINUSE='POWER';
      NO_LOAD_CHECK='Both';
      NO_IO_CHECK='Both';
      NO_ASSERT_CHECK='TRUE';
      NO_DIR_CHECK='TRUE';
      ALLOW_CONNECT='TRUE';
    'VSS_L23':
      PIN_NUMBER='(0,0,0,0,0,0,0,0,0,L23,0)';
      PINUSE='POWER';
      NO_LOAD_CHECK='Both';
      NO_IO_CHECK='Both';
      NO_ASSERT_CHECK='TRUE';
      NO_DIR_CHECK='TRUE';
      ALLOW_CONNECT='TRUE';
    'VSS_L20':
      PIN_NUMBER='(0,0,0,0,0,0,0,0,0,L20,0)';
      PINUSE='POWER';
      NO_LOAD_CHECK='Both';
      NO_IO_CHECK='Both';
      NO_ASSERT_CHECK='TRUE';
      NO_DIR_CHECK='TRUE';
      ALLOW_CONNECT='TRUE';
    'VSS_L16':
      PIN_NUMBER='(0,0,0,0,0,0,0,0,0,L16,0)';
      PINUSE='POWER';
      NO_LOAD_CHECK='Both';
      NO_IO_CHECK='Both';
      NO_ASSERT_CHECK='TRUE';
      NO_DIR_CHECK='TRUE';
      ALLOW_CONNECT='TRUE';
    'VSS_L10':
      PIN_NUMBER='(0,0,0,0,0,0,0,0,0,L10,0)';
      PINUSE='POWER';
      NO_LOAD_CHECK='Both';
      NO_IO_CHECK='Both';
      NO_ASSERT_CHECK='TRUE';
      NO_DIR_CHECK='TRUE';
      ALLOW_CONNECT='TRUE';
    'VSS_K5':
      PIN_NUMBER='(0,0,0,0,0,0,0,0,0,K5,0)';
      PINUSE='POWER';
      NO_LOAD_CHECK='Both';
      NO_IO_CHECK='Both';
      NO_ASSERT_CHECK='TRUE';
      NO_DIR_CHECK='TRUE';
      ALLOW_CONNECT='TRUE';
    'VSS_K39':
      PIN_NUMBER='(0,0,0,0,0,0,0,0,0,K39,0)';
      PINUSE='POWER';
      NO_LOAD_CHECK='Both';
      NO_IO_CHECK='Both';
      NO_ASSERT_CHECK='TRUE';
      NO_DIR_CHECK='TRUE';
      ALLOW_CONNECT='TRUE';
    'VSS_K34':
      PIN_NUMBER='(0,0,0,0,0,0,0,0,0,K34,0)';
      PINUSE='POWER';
      NO_LOAD_CHECK='Both';
      NO_IO_CHECK='Both';
      NO_ASSERT_CHECK='TRUE';
      NO_DIR_CHECK='TRUE';
      ALLOW_CONNECT='TRUE';
    'VSS_K24':
      PIN_NUMBER='(0,0,0,0,0,0,0,0,0,K24,0)';
      PINUSE='POWER';
      NO_LOAD_CHECK='Both';
      NO_IO_CHECK='Both';
      NO_ASSERT_CHECK='TRUE';
      NO_DIR_CHECK='TRUE';
      ALLOW_CONNECT='TRUE';
    'VSS_K15':
      PIN_NUMBER='(0,0,0,0,0,0,0,0,0,K15,0)';
      PINUSE='POWER';
      NO_LOAD_CHECK='Both';
      NO_IO_CHECK='Both';
      NO_ASSERT_CHECK='TRUE';
      NO_DIR_CHECK='TRUE';
      ALLOW_CONNECT='TRUE';
    'VSS_K11':
      PIN_NUMBER='(0,0,0,0,0,0,0,0,0,K11,0)';
      PINUSE='POWER';
      NO_LOAD_CHECK='Both';
      NO_IO_CHECK='Both';
      NO_ASSERT_CHECK='TRUE';
      NO_DIR_CHECK='TRUE';
      ALLOW_CONNECT='TRUE';
    'VSS_J26':
      PIN_NUMBER='(0,0,0,0,0,0,0,0,0,J26,0)';
      PINUSE='POWER';
      NO_LOAD_CHECK='Both';
      NO_IO_CHECK='Both';
      NO_ASSERT_CHECK='TRUE';
      NO_DIR_CHECK='TRUE';
      ALLOW_CONNECT='TRUE';
    'VSS_J20':
      PIN_NUMBER='(0,0,0,0,0,0,0,0,0,J20,0)';
      PINUSE='POWER';
      NO_LOAD_CHECK='Both';
      NO_IO_CHECK='Both';
      NO_ASSERT_CHECK='TRUE';
      NO_DIR_CHECK='TRUE';
      ALLOW_CONNECT='TRUE';
    'VSS_J13':
      PIN_NUMBER='(0,0,0,0,0,0,0,0,0,J13,0)';
      PINUSE='POWER';
      NO_LOAD_CHECK='Both';
      NO_IO_CHECK='Both';
      NO_ASSERT_CHECK='TRUE';
      NO_DIR_CHECK='TRUE';
      ALLOW_CONNECT='TRUE';
    'VSS_H8':
      PIN_NUMBER='(0,0,0,0,0,0,0,0,0,H8,0)';
      PINUSE='POWER';
      NO_LOAD_CHECK='Both';
      NO_IO_CHECK='Both';
      NO_ASSERT_CHECK='TRUE';
      NO_DIR_CHECK='TRUE';
      ALLOW_CONNECT='TRUE';
    'VSS_H5':
      PIN_NUMBER='(0,0,0,0,0,0,0,0,0,H5,0)';
      PINUSE='POWER';
      NO_LOAD_CHECK='Both';
      NO_IO_CHECK='Both';
      NO_ASSERT_CHECK='TRUE';
      NO_DIR_CHECK='TRUE';
      ALLOW_CONNECT='TRUE';
    'VSS_H39':
      PIN_NUMBER='(0,0,0,0,0,0,0,0,0,H39,0)';
      PINUSE='POWER';
      NO_LOAD_CHECK='Both';
      NO_IO_CHECK='Both';
      NO_ASSERT_CHECK='TRUE';
      NO_DIR_CHECK='TRUE';
      ALLOW_CONNECT='TRUE';
    'VSS_G26':
      PIN_NUMBER='(0,0,0,0,0,0,0,0,0,G26,0)';
      PINUSE='POWER';
      NO_LOAD_CHECK='Both';
      NO_IO_CHECK='Both';
      NO_ASSERT_CHECK='TRUE';
      NO_DIR_CHECK='TRUE';
      ALLOW_CONNECT='TRUE';
    'VSS_G20':
      PIN_NUMBER='(0,0,0,0,0,0,0,0,0,G20,0)';
      PINUSE='POWER';
      NO_LOAD_CHECK='Both';
      NO_IO_CHECK='Both';
      NO_ASSERT_CHECK='TRUE';
      NO_DIR_CHECK='TRUE';
      ALLOW_CONNECT='TRUE';
    'VSS_G13':
      PIN_NUMBER='(0,0,0,0,0,0,0,0,0,G13,0)';
      PINUSE='POWER';
      NO_LOAD_CHECK='Both';
      NO_IO_CHECK='Both';
      NO_ASSERT_CHECK='TRUE';
      NO_DIR_CHECK='TRUE';
      ALLOW_CONNECT='TRUE';
    'VSS_F39':
      PIN_NUMBER='(0,0,0,0,0,0,0,0,0,F39,0)';
      PINUSE='POWER';
      NO_LOAD_CHECK='Both';
      NO_IO_CHECK='Both';
      NO_ASSERT_CHECK='TRUE';
      NO_DIR_CHECK='TRUE';
      ALLOW_CONNECT='TRUE';
    'VSS_F34':
      PIN_NUMBER='(0,0,0,0,0,0,0,0,0,F34,0)';
      PINUSE='POWER';
      NO_LOAD_CHECK='Both';
      NO_IO_CHECK='Both';
      NO_ASSERT_CHECK='TRUE';
      NO_DIR_CHECK='TRUE';
      ALLOW_CONNECT='TRUE';
    'VSS_F31':
      PIN_NUMBER='(0,0,0,0,0,0,0,0,0,F31,0)';
      PINUSE='POWER';
      NO_LOAD_CHECK='Both';
      NO_IO_CHECK='Both';
      NO_ASSERT_CHECK='TRUE';
      NO_DIR_CHECK='TRUE';
      ALLOW_CONNECT='TRUE';
    'VSS_F24':
      PIN_NUMBER='(0,0,0,0,0,0,0,0,0,F24,0)';
      PINUSE='POWER';
      NO_LOAD_CHECK='Both';
      NO_IO_CHECK='Both';
      NO_ASSERT_CHECK='TRUE';
      NO_DIR_CHECK='TRUE';
      ALLOW_CONNECT='TRUE';
    'VSS_F15':
      PIN_NUMBER='(0,0,0,0,0,0,0,0,0,F15,0)';
      PINUSE='POWER';
      NO_LOAD_CHECK='Both';
      NO_IO_CHECK='Both';
      NO_ASSERT_CHECK='TRUE';
      NO_DIR_CHECK='TRUE';
      ALLOW_CONNECT='TRUE';
    'VSS_E6':
      PIN_NUMBER='(0,0,0,0,0,0,0,0,0,E6,0)';
      PINUSE='POWER';
      NO_LOAD_CHECK='Both';
      NO_IO_CHECK='Both';
      NO_ASSERT_CHECK='TRUE';
      NO_DIR_CHECK='TRUE';
      ALLOW_CONNECT='TRUE';
    'VSS_E38':
      PIN_NUMBER='(0,0,0,0,0,0,0,0,0,E38,0)';
      PINUSE='POWER';
      NO_LOAD_CHECK='Both';
      NO_IO_CHECK='Both';
      NO_ASSERT_CHECK='TRUE';
      NO_DIR_CHECK='TRUE';
      ALLOW_CONNECT='TRUE';
    'VSS_E36':
      PIN_NUMBER='(0,0,0,0,0,0,0,0,0,E36,0)';
      PINUSE='POWER';
      NO_LOAD_CHECK='Both';
      NO_IO_CHECK='Both';
      NO_ASSERT_CHECK='TRUE';
      NO_DIR_CHECK='TRUE';
      ALLOW_CONNECT='TRUE';
    'VSS_E34':
      PIN_NUMBER='(0,0,0,0,0,0,0,0,0,E34,0)';
      PINUSE='POWER';
      NO_LOAD_CHECK='Both';
      NO_IO_CHECK='Both';
      NO_ASSERT_CHECK='TRUE';
      NO_DIR_CHECK='TRUE';
      ALLOW_CONNECT='TRUE';
    'VSS_E32':
      PIN_NUMBER='(0,0,0,0,0,0,0,0,0,E32,0)';
      PINUSE='POWER';
      NO_LOAD_CHECK='Both';
      NO_IO_CHECK='Both';
      NO_ASSERT_CHECK='TRUE';
      NO_DIR_CHECK='TRUE';
      ALLOW_CONNECT='TRUE';
    'VSS_E30':
      PIN_NUMBER='(0,0,0,0,0,0,0,0,0,E30,0)';
      PINUSE='POWER';
      NO_LOAD_CHECK='Both';
      NO_IO_CHECK='Both';
      NO_ASSERT_CHECK='TRUE';
      NO_DIR_CHECK='TRUE';
      ALLOW_CONNECT='TRUE';
    'VSS_E28':
      PIN_NUMBER='(0,0,0,0,0,0,0,0,0,E28,0)';
      PINUSE='POWER';
      NO_LOAD_CHECK='Both';
      NO_IO_CHECK='Both';
      NO_ASSERT_CHECK='TRUE';
      NO_DIR_CHECK='TRUE';
      ALLOW_CONNECT='TRUE';
    'VSS_E26':
      PIN_NUMBER='(0,0,0,0,0,0,0,0,0,E26,0)';
      PINUSE='POWER';
      NO_LOAD_CHECK='Both';
      NO_IO_CHECK='Both';
      NO_ASSERT_CHECK='TRUE';
      NO_DIR_CHECK='TRUE';
      ALLOW_CONNECT='TRUE';
    'VSS_E24':
      PIN_NUMBER='(0,0,0,0,0,0,0,0,0,E24,0)';
      PINUSE='POWER';
      NO_LOAD_CHECK='Both';
      NO_IO_CHECK='Both';
      NO_ASSERT_CHECK='TRUE';
      NO_DIR_CHECK='TRUE';
      ALLOW_CONNECT='TRUE';
    'VSS_E22':
      PIN_NUMBER='(0,0,0,0,0,0,0,0,0,E22,0)';
      PINUSE='POWER';
      NO_LOAD_CHECK='Both';
      NO_IO_CHECK='Both';
      NO_ASSERT_CHECK='TRUE';
      NO_DIR_CHECK='TRUE';
      ALLOW_CONNECT='TRUE';
    'VSS_E20':
      PIN_NUMBER='(0,0,0,0,0,0,0,0,0,E20,0)';
      PINUSE='POWER';
      NO_LOAD_CHECK='Both';
      NO_IO_CHECK='Both';
      NO_ASSERT_CHECK='TRUE';
      NO_DIR_CHECK='TRUE';
      ALLOW_CONNECT='TRUE';
    'VSS_E18':
      PIN_NUMBER='(0,0,0,0,0,0,0,0,0,E18,0)';
      PINUSE='POWER';
      NO_LOAD_CHECK='Both';
      NO_IO_CHECK='Both';
      NO_ASSERT_CHECK='TRUE';
      NO_DIR_CHECK='TRUE';
      ALLOW_CONNECT='TRUE';
    'VSS_E16':
      PIN_NUMBER='(0,0,0,0,0,0,0,0,0,E16,0)';
      PINUSE='POWER';
      NO_LOAD_CHECK='Both';
      NO_IO_CHECK='Both';
      NO_ASSERT_CHECK='TRUE';
      NO_DIR_CHECK='TRUE';
      ALLOW_CONNECT='TRUE';
    'VSS_E14':
      PIN_NUMBER='(0,0,0,0,0,0,0,0,0,E14,0)';
      PINUSE='POWER';
      NO_LOAD_CHECK='Both';
      NO_IO_CHECK='Both';
      NO_ASSERT_CHECK='TRUE';
      NO_DIR_CHECK='TRUE';
      ALLOW_CONNECT='TRUE';
    'VSS_E12':
      PIN_NUMBER='(0,0,0,0,0,0,0,0,0,E12,0)';
      PINUSE='POWER';
      NO_LOAD_CHECK='Both';
      NO_IO_CHECK='Both';
      NO_ASSERT_CHECK='TRUE';
      NO_DIR_CHECK='TRUE';
      ALLOW_CONNECT='TRUE';
    'VSS_E10':
      PIN_NUMBER='(0,0,0,0,0,0,0,0,0,E10,0)';
      PINUSE='POWER';
      NO_LOAD_CHECK='Both';
      NO_IO_CHECK='Both';
      NO_ASSERT_CHECK='TRUE';
      NO_DIR_CHECK='TRUE';
      ALLOW_CONNECT='TRUE';
    'VSS_D9':
      PIN_NUMBER='(0,0,0,0,0,0,0,0,0,D9,0)';
      PINUSE='POWER';
      NO_LOAD_CHECK='Both';
      NO_IO_CHECK='Both';
      NO_ASSERT_CHECK='TRUE';
      NO_DIR_CHECK='TRUE';
      ALLOW_CONNECT='TRUE';
    'VSS_D5':
      PIN_NUMBER='(0,0,0,0,0,0,0,0,0,D5,0)';
      PINUSE='POWER';
      NO_LOAD_CHECK='Both';
      NO_IO_CHECK='Both';
      NO_ASSERT_CHECK='TRUE';
      NO_DIR_CHECK='TRUE';
      ALLOW_CONNECT='TRUE';
    'VSS_D29':
      PIN_NUMBER='(0,0,0,0,0,0,0,0,0,D29,0)';
      PINUSE='POWER';
      NO_LOAD_CHECK='Both';
      NO_IO_CHECK='Both';
      NO_ASSERT_CHECK='TRUE';
      NO_DIR_CHECK='TRUE';
      ALLOW_CONNECT='TRUE';
    'VSS_D13':
      PIN_NUMBER='(0,0,0,0,0,0,0,0,0,D13,0)';
      PINUSE='POWER';
      NO_LOAD_CHECK='Both';
      NO_IO_CHECK='Both';
      NO_ASSERT_CHECK='TRUE';
      NO_DIR_CHECK='TRUE';
      ALLOW_CONNECT='TRUE';
    'VSS_C4':
      PIN_NUMBER='(0,0,0,0,0,0,0,0,0,C4,0)';
      PINUSE='POWER';
      NO_LOAD_CHECK='Both';
      NO_IO_CHECK='Both';
      NO_ASSERT_CHECK='TRUE';
      NO_DIR_CHECK='TRUE';
      ALLOW_CONNECT='TRUE';
    'VSS_C26':
      PIN_NUMBER='(0,0,0,0,0,0,0,0,0,C26,0)';
      PINUSE='POWER';
      NO_LOAD_CHECK='Both';
      NO_IO_CHECK='Both';
      NO_ASSERT_CHECK='TRUE';
      NO_DIR_CHECK='TRUE';
      ALLOW_CONNECT='TRUE';
    'VSS_C24':
      PIN_NUMBER='(0,0,0,0,0,0,0,0,0,C24,0)';
      PINUSE='POWER';
      NO_LOAD_CHECK='Both';
      NO_IO_CHECK='Both';
      NO_ASSERT_CHECK='TRUE';
      NO_DIR_CHECK='TRUE';
      ALLOW_CONNECT='TRUE';
    'VSS_C22':
      PIN_NUMBER='(0,0,0,0,0,0,0,0,0,C22,0)';
      PINUSE='POWER';
      NO_LOAD_CHECK='Both';
      NO_IO_CHECK='Both';
      NO_ASSERT_CHECK='TRUE';
      NO_DIR_CHECK='TRUE';
      ALLOW_CONNECT='TRUE';
    'VSS_C20':
      PIN_NUMBER='(0,0,0,0,0,0,0,0,0,C20,0)';
      PINUSE='POWER';
      NO_LOAD_CHECK='Both';
      NO_IO_CHECK='Both';
      NO_ASSERT_CHECK='TRUE';
      NO_DIR_CHECK='TRUE';
      ALLOW_CONNECT='TRUE';
    'VSS_BG34':
      PIN_NUMBER='(0,0,0,0,0,0,0,0,0,BG34,0)';
      PINUSE='POWER';
      NO_LOAD_CHECK='Both';
      NO_IO_CHECK='Both';
      NO_ASSERT_CHECK='TRUE';
      NO_DIR_CHECK='TRUE';
      ALLOW_CONNECT='TRUE';
    'VSS_BG10':
      PIN_NUMBER='(0,0,0,0,0,0,0,0,0,BG10,0)';
      PINUSE='POWER';
      NO_LOAD_CHECK='Both';
      NO_IO_CHECK='Both';
      NO_ASSERT_CHECK='TRUE';
      NO_DIR_CHECK='TRUE';
      ALLOW_CONNECT='TRUE';
    'VSS_BF21':
      PIN_NUMBER='(0,0,0,0,0,0,0,0,0,BF21,0)';
      PINUSE='POWER';
      NO_LOAD_CHECK='Both';
      NO_IO_CHECK='Both';
      NO_ASSERT_CHECK='TRUE';
      NO_DIR_CHECK='TRUE';
      ALLOW_CONNECT='TRUE';
    'VSS_BE34':
      PIN_NUMBER='(0,0,0,0,0,0,0,0,0,BE34,0)';
      PINUSE='POWER';
      NO_LOAD_CHECK='Both';
      NO_IO_CHECK='Both';
      NO_ASSERT_CHECK='TRUE';
      NO_DIR_CHECK='TRUE';
      ALLOW_CONNECT='TRUE';
    'VSS_BE10':
      PIN_NUMBER='(0,0,0,0,0,0,0,0,0,BE10,0)';
      PINUSE='POWER';
      NO_LOAD_CHECK='Both';
      NO_IO_CHECK='Both';
      NO_ASSERT_CHECK='TRUE';
      NO_DIR_CHECK='TRUE';
      ALLOW_CONNECT='TRUE';
    'VSS_BD39':
      PIN_NUMBER='(0,0,0,0,0,0,0,0,0,BD39,0)';
      PINUSE='POWER';
      NO_LOAD_CHECK='Both';
      NO_IO_CHECK='Both';
      NO_ASSERT_CHECK='TRUE';
      NO_DIR_CHECK='TRUE';
      ALLOW_CONNECT='TRUE';
    'VSS_BD21':
      PIN_NUMBER='(0,0,0,0,0,0,0,0,0,BD21,0)';
      PINUSE='POWER';
      NO_LOAD_CHECK='Both';
      NO_IO_CHECK='Both';
      NO_ASSERT_CHECK='TRUE';
      NO_DIR_CHECK='TRUE';
      ALLOW_CONNECT='TRUE';
    'VSS_BC8':
      PIN_NUMBER='(0,0,0,0,0,0,0,0,0,BC8,0)';
      PINUSE='POWER';
      NO_LOAD_CHECK='Both';
      NO_IO_CHECK='Both';
      NO_ASSERT_CHECK='TRUE';
      NO_DIR_CHECK='TRUE';
      ALLOW_CONNECT='TRUE';
    'VSS_BC6':
      PIN_NUMBER='(0,0,0,0,0,0,0,0,0,BC6,0)';
      PINUSE='POWER';
      NO_LOAD_CHECK='Both';
      NO_IO_CHECK='Both';
      NO_ASSERT_CHECK='TRUE';
      NO_DIR_CHECK='TRUE';
      ALLOW_CONNECT='TRUE';
    'VSS_BC38':
      PIN_NUMBER='(0,0,0,0,0,0,0,0,0,BC38,0)';
      PINUSE='POWER';
      NO_LOAD_CHECK='Both';
      NO_IO_CHECK='Both';
      NO_ASSERT_CHECK='TRUE';
      NO_DIR_CHECK='TRUE';
      ALLOW_CONNECT='TRUE';
    'VSS_BC34':
      PIN_NUMBER='(0,0,0,0,0,0,0,0,0,BC34,0)';
      PINUSE='POWER';
      NO_LOAD_CHECK='Both';
      NO_IO_CHECK='Both';
      NO_ASSERT_CHECK='TRUE';
      NO_DIR_CHECK='TRUE';
      ALLOW_CONNECT='TRUE';
    'VSS_BC32':
      PIN_NUMBER='(0,0,0,0,0,0,0,0,0,BC32,0)';
      PINUSE='POWER';
      NO_LOAD_CHECK='Both';
      NO_IO_CHECK='Both';
      NO_ASSERT_CHECK='TRUE';
      NO_DIR_CHECK='TRUE';
      ALLOW_CONNECT='TRUE';
    'VSS_BC30':
      PIN_NUMBER='(0,0,0,0,0,0,0,0,0,BC30,0)';
      PINUSE='POWER';
      NO_LOAD_CHECK='Both';
      NO_IO_CHECK='Both';
      NO_ASSERT_CHECK='TRUE';
      NO_DIR_CHECK='TRUE';
      ALLOW_CONNECT='TRUE';
    'VSS_BC28':
      PIN_NUMBER='(0,0,0,0,0,0,0,0,0,BC28,0)';
      PINUSE='POWER';
      NO_LOAD_CHECK='Both';
      NO_IO_CHECK='Both';
      NO_ASSERT_CHECK='TRUE';
      NO_DIR_CHECK='TRUE';
      ALLOW_CONNECT='TRUE';
    'VSS_BC26':
      PIN_NUMBER='(0,0,0,0,0,0,0,0,0,BC26,0)';
      PINUSE='POWER';
      NO_LOAD_CHECK='Both';
      NO_IO_CHECK='Both';
      NO_ASSERT_CHECK='TRUE';
      NO_DIR_CHECK='TRUE';
      ALLOW_CONNECT='TRUE';
    'VSS_BC24':
      PIN_NUMBER='(0,0,0,0,0,0,0,0,0,BC24,0)';
      PINUSE='POWER';
      NO_LOAD_CHECK='Both';
      NO_IO_CHECK='Both';
      NO_ASSERT_CHECK='TRUE';
      NO_DIR_CHECK='TRUE';
      ALLOW_CONNECT='TRUE';
    'VSS_BC22':
      PIN_NUMBER='(0,0,0,0,0,0,0,0,0,BC22,0)';
      PINUSE='POWER';
      NO_LOAD_CHECK='Both';
      NO_IO_CHECK='Both';
      NO_ASSERT_CHECK='TRUE';
      NO_DIR_CHECK='TRUE';
      ALLOW_CONNECT='TRUE';
    'VSS_BC20':
      PIN_NUMBER='(0,0,0,0,0,0,0,0,0,BC20,0)';
      PINUSE='POWER';
      NO_LOAD_CHECK='Both';
      NO_IO_CHECK='Both';
      NO_ASSERT_CHECK='TRUE';
      NO_DIR_CHECK='TRUE';
      ALLOW_CONNECT='TRUE';
    'VSS_BC18':
      PIN_NUMBER='(0,0,0,0,0,0,0,0,0,BC18,0)';
      PINUSE='POWER';
      NO_LOAD_CHECK='Both';
      NO_IO_CHECK='Both';
      NO_ASSERT_CHECK='TRUE';
      NO_DIR_CHECK='TRUE';
      ALLOW_CONNECT='TRUE';
    'VSS_BC16':
      PIN_NUMBER='(0,0,0,0,0,0,0,0,0,BC16,0)';
      PINUSE='POWER';
      NO_LOAD_CHECK='Both';
      NO_IO_CHECK='Both';
      NO_ASSERT_CHECK='TRUE';
      NO_DIR_CHECK='TRUE';
      ALLOW_CONNECT='TRUE';
    'VSS_BC14':
      PIN_NUMBER='(0,0,0,0,0,0,0,0,0,BC14,0)';
      PINUSE='POWER';
      NO_LOAD_CHECK='Both';
      NO_IO_CHECK='Both';
      NO_ASSERT_CHECK='TRUE';
      NO_DIR_CHECK='TRUE';
      ALLOW_CONNECT='TRUE';
    'VSS_BC12':
      PIN_NUMBER='(0,0,0,0,0,0,0,0,0,BC12,0)';
      PINUSE='POWER';
      NO_LOAD_CHECK='Both';
      NO_IO_CHECK='Both';
      NO_ASSERT_CHECK='TRUE';
      NO_DIR_CHECK='TRUE';
      ALLOW_CONNECT='TRUE';
    'VSS_BC10':
      PIN_NUMBER='(0,0,0,0,0,0,0,0,0,BC10,0)';
      PINUSE='POWER';
      NO_LOAD_CHECK='Both';
      NO_IO_CHECK='Both';
      NO_ASSERT_CHECK='TRUE';
      NO_DIR_CHECK='TRUE';
      ALLOW_CONNECT='TRUE';
    'VSS_BB5':
      PIN_NUMBER='(0,0,0,0,0,0,0,0,0,BB5,0)';
      PINUSE='POWER';
      NO_LOAD_CHECK='Both';
      NO_IO_CHECK='Both';
      NO_ASSERT_CHECK='TRUE';
      NO_DIR_CHECK='TRUE';
      ALLOW_CONNECT='TRUE';
    'VSS_BB39':
      PIN_NUMBER='(0,0,0,0,0,0,0,0,0,BB39,0)';
      PINUSE='POWER';
      NO_LOAD_CHECK='Both';
      NO_IO_CHECK='Both';
      NO_ASSERT_CHECK='TRUE';
      NO_DIR_CHECK='TRUE';
      ALLOW_CONNECT='TRUE';
    'VSS_B9':
      PIN_NUMBER='(0,0,0,0,0,0,0,0,0,B9,0)';
      PINUSE='POWER';
      NO_LOAD_CHECK='Both';
      NO_IO_CHECK='Both';
      NO_ASSERT_CHECK='TRUE';
      NO_DIR_CHECK='TRUE';
      ALLOW_CONNECT='TRUE';
    'VSS_B29':
      PIN_NUMBER='(0,0,0,0,0,0,0,0,0,B29,0)';
      PINUSE='POWER';
      NO_LOAD_CHECK='Both';
      NO_IO_CHECK='Both';
      NO_ASSERT_CHECK='TRUE';
      NO_DIR_CHECK='TRUE';
      ALLOW_CONNECT='TRUE';
    'VSS_B13':
      PIN_NUMBER='(0,0,0,0,0,0,0,0,0,B13,0)';
      PINUSE='POWER';
      NO_LOAD_CHECK='Both';
      NO_IO_CHECK='Both';
      NO_ASSERT_CHECK='TRUE';
      NO_DIR_CHECK='TRUE';
      ALLOW_CONNECT='TRUE';
    'VSS_AY8':
      PIN_NUMBER='(0,0,0,0,0,0,0,0,0,AY8,0)';
      PINUSE='POWER';
      NO_LOAD_CHECK='Both';
      NO_IO_CHECK='Both';
      NO_ASSERT_CHECK='TRUE';
      NO_DIR_CHECK='TRUE';
      ALLOW_CONNECT='TRUE';
    'VSS_AY5':
      PIN_NUMBER='(0,0,0,0,0,0,0,0,0,AY5,0)';
      PINUSE='POWER';
      NO_LOAD_CHECK='Both';
      NO_IO_CHECK='Both';
      NO_ASSERT_CHECK='TRUE';
      NO_DIR_CHECK='TRUE';
      ALLOW_CONNECT='TRUE';
    'VSS_AY37':
      PIN_NUMBER='(0,0,0,0,0,0,0,0,0,AY37,0)';
      PINUSE='POWER';
      NO_LOAD_CHECK='Both';
      NO_IO_CHECK='Both';
      NO_ASSERT_CHECK='TRUE';
      NO_DIR_CHECK='TRUE';
      ALLOW_CONNECT='TRUE';
    'VSS_AY34':
      PIN_NUMBER='(0,0,0,0,0,0,0,0,0,AY34,0)';
      PINUSE='POWER';
      NO_LOAD_CHECK='Both';
      NO_IO_CHECK='Both';
      NO_ASSERT_CHECK='TRUE';
      NO_DIR_CHECK='TRUE';
      ALLOW_CONNECT='TRUE';
    'VSS_AY31':
      PIN_NUMBER='(0,0,0,0,0,0,0,0,0,AY31,0)';
      PINUSE='POWER';
      NO_LOAD_CHECK='Both';
      NO_IO_CHECK='Both';
      NO_ASSERT_CHECK='TRUE';
      NO_DIR_CHECK='TRUE';
      ALLOW_CONNECT='TRUE';
    'VSS_AY28':
      PIN_NUMBER='(0,0,0,0,0,0,0,0,0,AY28,0)';
      PINUSE='POWER';
      NO_LOAD_CHECK='Both';
      NO_IO_CHECK='Both';
      NO_ASSERT_CHECK='TRUE';
      NO_DIR_CHECK='TRUE';
      ALLOW_CONNECT='TRUE';
    'VSS_AY39':
      PIN_NUMBER='(0,0,0,0,0,0,0,0,0,AY39,0)';
      PINUSE='POWER';
      NO_LOAD_CHECK='Both';
      NO_IO_CHECK='Both';
      NO_ASSERT_CHECK='TRUE';
      NO_DIR_CHECK='TRUE';
      ALLOW_CONNECT='TRUE';
    'VSS_F41':
      PIN_NUMBER='(0,0,0,0,0,0,0,0,0,F41,0)';
      PINUSE='POWER';
      NO_LOAD_CHECK='Both';
      NO_IO_CHECK='Both';
      NO_ASSERT_CHECK='TRUE';
      NO_DIR_CHECK='TRUE';
      ALLOW_CONNECT='TRUE';
    'VSS_E40':
      PIN_NUMBER='(0,0,0,0,0,0,0,0,0,E40,0)';
      PINUSE='POWER';
      NO_LOAD_CHECK='Both';
      NO_IO_CHECK='Both';
      NO_ASSERT_CHECK='TRUE';
      NO_DIR_CHECK='TRUE';
      ALLOW_CONNECT='TRUE';
    'VSS_BD5':
      PIN_NUMBER='(0,0,0,0,0,0,0,0,0,BD5,0)';
      PINUSE='POWER';
      NO_LOAD_CHECK='Both';
      NO_IO_CHECK='Both';
      NO_ASSERT_CHECK='TRUE';
      NO_DIR_CHECK='TRUE';
      ALLOW_CONNECT='TRUE';
    'VSS_BC36':
      PIN_NUMBER='(0,0,0,0,0,0,0,0,0,BC36,0)';
      PINUSE='POWER';
      NO_LOAD_CHECK='Both';
      NO_IO_CHECK='Both';
      NO_ASSERT_CHECK='TRUE';
      NO_DIR_CHECK='TRUE';
      ALLOW_CONNECT='TRUE';
    'VSS_AY3':
      PIN_NUMBER='(0,0,0,0,0,0,0,0,0,AY3,0)';
      PINUSE='POWER';
      NO_LOAD_CHECK='Both';
      NO_IO_CHECK='Both';
      NO_ASSERT_CHECK='TRUE';
      NO_DIR_CHECK='TRUE';
      ALLOW_CONNECT='TRUE';
    'VSS_C38':
      PIN_NUMBER='(0,0,0,0,0,0,0,0,0,C38,0)';
      PINUSE='POWER';
      NO_LOAD_CHECK='Both';
      NO_IO_CHECK='Both';
      NO_ASSERT_CHECK='TRUE';
      NO_DIR_CHECK='TRUE';
      ALLOW_CONNECT='TRUE';
    'VSS_B39':
      PIN_NUMBER='(0,0,0,0,0,0,0,0,0,B39,0)';
      PINUSE='POWER';
      NO_LOAD_CHECK='Both';
      NO_IO_CHECK='Both';
      NO_ASSERT_CHECK='TRUE';
      NO_DIR_CHECK='TRUE';
      ALLOW_CONNECT='TRUE';
    'VSS_E8':
      PIN_NUMBER='(0,0,0,0,0,0,0,0,0,E8,0)';
      PINUSE='POWER';
      NO_LOAD_CHECK='Both';
      NO_IO_CHECK='Both';
      NO_ASSERT_CHECK='TRUE';
      NO_DIR_CHECK='TRUE';
      ALLOW_CONNECT='TRUE';
    'VSS_D43':
      PIN_NUMBER='(0,0,0,0,0,0,0,0,0,0,D43)';
      PINUSE='POWER';
      NO_LOAD_CHECK='Both';
      NO_IO_CHECK='Both';
      NO_ASSERT_CHECK='TRUE';
      NO_DIR_CHECK='TRUE';
      ALLOW_CONNECT='TRUE';
    'VSS_D1':
      PIN_NUMBER='(0,0,0,0,0,0,0,0,0,0,D1)';
      PINUSE='POWER';
      NO_LOAD_CHECK='Both';
      NO_IO_CHECK='Both';
      NO_ASSERT_CHECK='TRUE';
      NO_DIR_CHECK='TRUE';
      ALLOW_CONNECT='TRUE';
    'VSS_C43':
      PIN_NUMBER='(0,0,0,0,0,0,0,0,0,0,C43)';
      PINUSE='POWER';
      NO_LOAD_CHECK='Both';
      NO_IO_CHECK='Both';
      NO_ASSERT_CHECK='TRUE';
      NO_DIR_CHECK='TRUE';
      ALLOW_CONNECT='TRUE';
    'VSS_C41':
      PIN_NUMBER='(0,0,0,0,0,0,0,0,0,0,C41)';
      PINUSE='POWER';
      NO_LOAD_CHECK='Both';
      NO_IO_CHECK='Both';
      NO_ASSERT_CHECK='TRUE';
      NO_DIR_CHECK='TRUE';
      ALLOW_CONNECT='TRUE';
    'VSS_C3':
      PIN_NUMBER='(0,0,0,0,0,0,0,0,0,0,C3)';
      PINUSE='POWER';
      NO_LOAD_CHECK='Both';
      NO_IO_CHECK='Both';
      NO_ASSERT_CHECK='TRUE';
      NO_DIR_CHECK='TRUE';
      ALLOW_CONNECT='TRUE';
    'VSS_BG41':
      PIN_NUMBER='(0,0,0,0,0,0,0,0,0,0,BG41)';
      PINUSE='POWER';
      NO_LOAD_CHECK='Both';
      NO_IO_CHECK='Both';
      NO_ASSERT_CHECK='TRUE';
      NO_DIR_CHECK='TRUE';
      ALLOW_CONNECT='TRUE';
    'VSS_BE43':
      PIN_NUMBER='(0,0,0,0,0,0,0,0,0,0,BE43)';
      PINUSE='POWER';
      NO_LOAD_CHECK='Both';
      NO_IO_CHECK='Both';
      NO_ASSERT_CHECK='TRUE';
      NO_DIR_CHECK='TRUE';
      ALLOW_CONNECT='TRUE';
    'VSS_BE41':
      PIN_NUMBER='(0,0,0,0,0,0,0,0,0,0,BE41)';
      PINUSE='POWER';
      NO_LOAD_CHECK='Both';
      NO_IO_CHECK='Both';
      NO_ASSERT_CHECK='TRUE';
      NO_DIR_CHECK='TRUE';
      ALLOW_CONNECT='TRUE';
    'VSS_BE3':
      PIN_NUMBER='(0,0,0,0,0,0,0,0,0,0,BE3)';
      PINUSE='POWER';
      NO_LOAD_CHECK='Both';
      NO_IO_CHECK='Both';
      NO_ASSERT_CHECK='TRUE';
      NO_DIR_CHECK='TRUE';
      ALLOW_CONNECT='TRUE';
    'VSS_BE1':
      PIN_NUMBER='(0,0,0,0,0,0,0,0,0,0,BE1)';
      PINUSE='POWER';
      NO_LOAD_CHECK='Both';
      NO_IO_CHECK='Both';
      NO_ASSERT_CHECK='TRUE';
      NO_DIR_CHECK='TRUE';
      ALLOW_CONNECT='TRUE';
    'VSS_BD43':
      PIN_NUMBER='(0,0,0,0,0,0,0,0,0,0,BD43)';
      PINUSE='POWER';
      NO_LOAD_CHECK='Both';
      NO_IO_CHECK='Both';
      NO_ASSERT_CHECK='TRUE';
      NO_DIR_CHECK='TRUE';
      ALLOW_CONNECT='TRUE';
    'VSS_BD1':
      PIN_NUMBER='(0,0,0,0,0,0,0,0,0,0,BD1)';
      PINUSE='POWER';
      NO_LOAD_CHECK='Both';
      NO_IO_CHECK='Both';
      NO_ASSERT_CHECK='TRUE';
      NO_DIR_CHECK='TRUE';
      ALLOW_CONNECT='TRUE';
    'VSS_E42':
      PIN_NUMBER='(0,0,0,0,0,0,0,0,0,0,E42)';
      PINUSE='POWER';
      NO_LOAD_CHECK='Both';
      NO_IO_CHECK='Both';
      NO_ASSERT_CHECK='TRUE';
      NO_DIR_CHECK='TRUE';
      ALLOW_CONNECT='TRUE';
    'VSS_E2':
      PIN_NUMBER='(0,0,0,0,0,0,0,0,0,0,E2)';
      PINUSE='POWER';
      NO_LOAD_CHECK='Both';
      NO_IO_CHECK='Both';
      NO_ASSERT_CHECK='TRUE';
      NO_DIR_CHECK='TRUE';
      ALLOW_CONNECT='TRUE';
    'VSS_D41':
      PIN_NUMBER='(0,0,0,0,0,0,0,0,0,0,D41)';
      PINUSE='POWER';
      NO_LOAD_CHECK='Both';
      NO_IO_CHECK='Both';
      NO_ASSERT_CHECK='TRUE';
      NO_DIR_CHECK='TRUE';
      ALLOW_CONNECT='TRUE';
    'VSS_D3':
      PIN_NUMBER='(0,0,0,0,0,0,0,0,0,0,D3)';
      PINUSE='POWER';
      NO_LOAD_CHECK='Both';
      NO_IO_CHECK='Both';
      NO_ASSERT_CHECK='TRUE';
      NO_DIR_CHECK='TRUE';
      ALLOW_CONNECT='TRUE';
    'VSS_BD41':
      PIN_NUMBER='(0,0,0,0,0,0,0,0,0,0,BD41)';
      PINUSE='POWER';
      NO_LOAD_CHECK='Both';
      NO_IO_CHECK='Both';
      NO_ASSERT_CHECK='TRUE';
      NO_DIR_CHECK='TRUE';
      ALLOW_CONNECT='TRUE';
    'VSS_BD3':
      PIN_NUMBER='(0,0,0,0,0,0,0,0,0,0,BD3)';
      PINUSE='POWER';
      NO_LOAD_CHECK='Both';
      NO_IO_CHECK='Both';
      NO_ASSERT_CHECK='TRUE';
      NO_DIR_CHECK='TRUE';
      ALLOW_CONNECT='TRUE';
    'VSS_BC42':
      PIN_NUMBER='(0,0,0,0,0,0,0,0,0,0,BC42)';
      PINUSE='POWER';
      NO_LOAD_CHECK='Both';
      NO_IO_CHECK='Both';
      NO_ASSERT_CHECK='TRUE';
      NO_DIR_CHECK='TRUE';
      ALLOW_CONNECT='TRUE';
    'VSS_BC2':
      PIN_NUMBER='(0,0,0,0,0,0,0,0,0,0,BC2)';
      PINUSE='POWER';
      NO_LOAD_CHECK='Both';
      NO_IO_CHECK='Both';
      NO_ASSERT_CHECK='TRUE';
      NO_DIR_CHECK='TRUE';
      ALLOW_CONNECT='TRUE';
    'VSS_F43':
      PIN_NUMBER='(0,0,0,0,0,0,0,0,0,0,F43)';
      PINUSE='POWER';
      NO_LOAD_CHECK='Both';
      NO_IO_CHECK='Both';
      NO_ASSERT_CHECK='TRUE';
      NO_DIR_CHECK='TRUE';
      ALLOW_CONNECT='TRUE';
    'VSS_BG6':
      PIN_NUMBER='(0,0,0,0,0,0,0,0,0,0,BG6)';
      PINUSE='POWER';
      NO_LOAD_CHECK='Both';
      NO_IO_CHECK='Both';
      NO_ASSERT_CHECK='TRUE';
      NO_DIR_CHECK='TRUE';
      ALLOW_CONNECT='TRUE';
    'VSS_BG4':
      PIN_NUMBER='(0,0,0,0,0,0,0,0,0,0,BG4)';
      PINUSE='POWER';
      NO_LOAD_CHECK='Both';
      NO_IO_CHECK='Both';
      NO_ASSERT_CHECK='TRUE';
      NO_DIR_CHECK='TRUE';
      ALLOW_CONNECT='TRUE';
    'VSS_BG38':
      PIN_NUMBER='(0,0,0,0,0,0,0,0,0,0,BG38)';
      PINUSE='POWER';
      NO_LOAD_CHECK='Both';
      NO_IO_CHECK='Both';
      NO_ASSERT_CHECK='TRUE';
      NO_DIR_CHECK='TRUE';
      ALLOW_CONNECT='TRUE';
    'VSS_BB1':
      PIN_NUMBER='(0,0,0,0,0,0,0,0,0,0,BB1)';
      PINUSE='POWER';
      NO_LOAD_CHECK='Both';
      NO_IO_CHECK='Both';
      NO_ASSERT_CHECK='TRUE';
      NO_DIR_CHECK='TRUE';
      ALLOW_CONNECT='TRUE';
    'VSS_A6':
      PIN_NUMBER='(0,0,0,0,0,0,0,0,0,0,A6)';
      PINUSE='POWER';
      NO_LOAD_CHECK='Both';
      NO_IO_CHECK='Both';
      NO_ASSERT_CHECK='TRUE';
      NO_DIR_CHECK='TRUE';
      ALLOW_CONNECT='TRUE';
    'VSS_A40':
      PIN_NUMBER='(0,0,0,0,0,0,0,0,0,0,A40)';
      PINUSE='POWER';
      NO_LOAD_CHECK='Both';
      NO_IO_CHECK='Both';
      NO_ASSERT_CHECK='TRUE';
      NO_DIR_CHECK='TRUE';
      ALLOW_CONNECT='TRUE';
    'VSS_A38':
      PIN_NUMBER='(0,0,0,0,0,0,0,0,0,0,A38)';
      PINUSE='POWER';
      NO_LOAD_CHECK='Both';
      NO_IO_CHECK='Both';
      NO_ASSERT_CHECK='TRUE';
      NO_DIR_CHECK='TRUE';
      ALLOW_CONNECT='TRUE';
    'VSS_AY24':
      PIN_NUMBER='(0,0,0,0,0,0,0,0,0,0,AY24)';
      PINUSE='POWER';
      NO_LOAD_CHECK='Both';
      NO_IO_CHECK='Both';
      NO_ASSERT_CHECK='TRUE';
      NO_DIR_CHECK='TRUE';
      ALLOW_CONNECT='TRUE';
    'VSS_AY21':
      PIN_NUMBER='(0,0,0,0,0,0,0,0,0,0,AY21)';
      PINUSE='POWER';
      NO_LOAD_CHECK='Both';
      NO_IO_CHECK='Both';
      NO_ASSERT_CHECK='TRUE';
      NO_DIR_CHECK='TRUE';
      ALLOW_CONNECT='TRUE';
    'VSS_AY18':
      PIN_NUMBER='(0,0,0,0,0,0,0,0,0,0,AY18)';
      PINUSE='POWER';
      NO_LOAD_CHECK='Both';
      NO_IO_CHECK='Both';
      NO_ASSERT_CHECK='TRUE';
      NO_DIR_CHECK='TRUE';
      ALLOW_CONNECT='TRUE';
    'VSS_AY15':
      PIN_NUMBER='(0,0,0,0,0,0,0,0,0,0,AY15)';
      PINUSE='POWER';
      NO_LOAD_CHECK='Both';
      NO_IO_CHECK='Both';
      NO_ASSERT_CHECK='TRUE';
      NO_DIR_CHECK='TRUE';
      ALLOW_CONNECT='TRUE';
    'VSS_AY11':
      PIN_NUMBER='(0,0,0,0,0,0,0,0,0,0,AY11)';
      PINUSE='POWER';
      NO_LOAD_CHECK='Both';
      NO_IO_CHECK='Both';
      NO_ASSERT_CHECK='TRUE';
      NO_DIR_CHECK='TRUE';
      ALLOW_CONNECT='TRUE';
    'VSS_AW7':
      PIN_NUMBER='(0,0,0,0,0,0,0,0,0,0,AW7)';
      PINUSE='POWER';
      NO_LOAD_CHECK='Both';
      NO_IO_CHECK='Both';
      NO_ASSERT_CHECK='TRUE';
      NO_DIR_CHECK='TRUE';
      ALLOW_CONNECT='TRUE';
    'VSS_AV8':
      PIN_NUMBER='(0,0,0,0,0,0,0,0,0,0,AV8)';
      PINUSE='POWER';
      NO_LOAD_CHECK='Both';
      NO_IO_CHECK='Both';
      NO_ASSERT_CHECK='TRUE';
      NO_DIR_CHECK='TRUE';
      ALLOW_CONNECT='TRUE';
    'VSS_AV5':
      PIN_NUMBER='(0,0,0,0,0,0,0,0,0,0,AV5)';
      PINUSE='POWER';
      NO_LOAD_CHECK='Both';
      NO_IO_CHECK='Both';
      NO_ASSERT_CHECK='TRUE';
      NO_DIR_CHECK='TRUE';
      ALLOW_CONNECT='TRUE';
    'VSS_AV39':
      PIN_NUMBER='(0,0,0,0,0,0,0,0,0,0,AV39)';
      PINUSE='POWER';
      NO_LOAD_CHECK='Both';
      NO_IO_CHECK='Both';
      NO_ASSERT_CHECK='TRUE';
      NO_DIR_CHECK='TRUE';
      ALLOW_CONNECT='TRUE';
    'VSS_AV37':
      PIN_NUMBER='(0,0,0,0,0,0,0,0,0,0,AV37)';
      PINUSE='POWER';
      NO_LOAD_CHECK='Both';
      NO_IO_CHECK='Both';
      NO_ASSERT_CHECK='TRUE';
      NO_DIR_CHECK='TRUE';
      ALLOW_CONNECT='TRUE';
    'VSS_AU36':
      PIN_NUMBER='(0,0,0,0,0,0,0,0,0,0,AU36)';
      PINUSE='POWER';
      NO_LOAD_CHECK='Both';
      NO_IO_CHECK='Both';
      NO_ASSERT_CHECK='TRUE';
      NO_DIR_CHECK='TRUE';
      ALLOW_CONNECT='TRUE';
    'VSS_AU32':
      PIN_NUMBER='(0,0,0,0,0,0,0,0,0,0,AU32)';
      PINUSE='POWER';
      NO_LOAD_CHECK='Both';
      NO_IO_CHECK='Both';
      NO_ASSERT_CHECK='TRUE';
      NO_DIR_CHECK='TRUE';
      ALLOW_CONNECT='TRUE';
    'VSS_AU29':
      PIN_NUMBER='(0,0,0,0,0,0,0,0,0,0,AU29)';
      PINUSE='POWER';
      NO_LOAD_CHECK='Both';
      NO_IO_CHECK='Both';
      NO_ASSERT_CHECK='TRUE';
      NO_DIR_CHECK='TRUE';
      ALLOW_CONNECT='TRUE';
    'VSS_AU26':
      PIN_NUMBER='(0,0,0,0,0,0,0,0,0,0,AU26)';
      PINUSE='POWER';
      NO_LOAD_CHECK='Both';
      NO_IO_CHECK='Both';
      NO_ASSERT_CHECK='TRUE';
      NO_DIR_CHECK='TRUE';
      ALLOW_CONNECT='TRUE';
    'VSS_AU23':
      PIN_NUMBER='(0,0,0,0,0,0,0,0,0,0,AU23)';
      PINUSE='POWER';
      NO_LOAD_CHECK='Both';
      NO_IO_CHECK='Both';
      NO_ASSERT_CHECK='TRUE';
      NO_DIR_CHECK='TRUE';
      ALLOW_CONNECT='TRUE';
    'VSS_AU20':
      PIN_NUMBER='(0,0,0,0,0,0,0,0,0,0,AU20)';
      PINUSE='POWER';
      NO_LOAD_CHECK='Both';
      NO_IO_CHECK='Both';
      NO_ASSERT_CHECK='TRUE';
      NO_DIR_CHECK='TRUE';
      ALLOW_CONNECT='TRUE';
    'VSS_AT8':
      PIN_NUMBER='(0,0,0,0,0,0,0,0,0,0,AT8)';
      PINUSE='POWER';
      NO_LOAD_CHECK='Both';
      NO_IO_CHECK='Both';
      NO_ASSERT_CHECK='TRUE';
      NO_DIR_CHECK='TRUE';
      ALLOW_CONNECT='TRUE';
    'VSS_AT5':
      PIN_NUMBER='(0,0,0,0,0,0,0,0,0,0,AT5)';
      PINUSE='POWER';
      NO_LOAD_CHECK='Both';
      NO_IO_CHECK='Both';
      NO_ASSERT_CHECK='TRUE';
      NO_DIR_CHECK='TRUE';
      ALLOW_CONNECT='TRUE';
    'VSS_AT39':
      PIN_NUMBER='(0,0,0,0,0,0,0,0,0,0,AT39)';
      PINUSE='POWER';
      NO_LOAD_CHECK='Both';
      NO_IO_CHECK='Both';
      NO_ASSERT_CHECK='TRUE';
      NO_DIR_CHECK='TRUE';
      ALLOW_CONNECT='TRUE';
    'VSS_AT34':
      PIN_NUMBER='(0,0,0,0,0,0,0,0,0,0,AT34)';
      PINUSE='POWER';
      NO_LOAD_CHECK='Both';
      NO_IO_CHECK='Both';
      NO_ASSERT_CHECK='TRUE';
      NO_DIR_CHECK='TRUE';
      ALLOW_CONNECT='TRUE';
    'VSS_AT31':
      PIN_NUMBER='(0,0,0,0,0,0,0,0,0,0,AT31)';
      PINUSE='POWER';
      NO_LOAD_CHECK='Both';
      NO_IO_CHECK='Both';
      NO_ASSERT_CHECK='TRUE';
      NO_DIR_CHECK='TRUE';
      ALLOW_CONNECT='TRUE';
    'VSS_AT28':
      PIN_NUMBER='(0,0,0,0,0,0,0,0,0,0,AT28)';
      PINUSE='POWER';
      NO_LOAD_CHECK='Both';
      NO_IO_CHECK='Both';
      NO_ASSERT_CHECK='TRUE';
      NO_DIR_CHECK='TRUE';
      ALLOW_CONNECT='TRUE';
    'VSS_AT24':
      PIN_NUMBER='(0,0,0,0,0,0,0,0,0,0,AT24)';
      PINUSE='POWER';
      NO_LOAD_CHECK='Both';
      NO_IO_CHECK='Both';
      NO_ASSERT_CHECK='TRUE';
      NO_DIR_CHECK='TRUE';
      ALLOW_CONNECT='TRUE';
    'VSS_AT21':
      PIN_NUMBER='(0,0,0,0,0,0,0,0,0,0,AT21)';
      PINUSE='POWER';
      NO_LOAD_CHECK='Both';
      NO_IO_CHECK='Both';
      NO_ASSERT_CHECK='TRUE';
      NO_DIR_CHECK='TRUE';
      ALLOW_CONNECT='TRUE';
    'VSS_AT15':
      PIN_NUMBER='(0,0,0,0,0,0,0,0,0,0,AT15)';
      PINUSE='POWER';
      NO_LOAD_CHECK='Both';
      NO_IO_CHECK='Both';
      NO_ASSERT_CHECK='TRUE';
      NO_DIR_CHECK='TRUE';
      ALLOW_CONNECT='TRUE';
    'VSS_AT11':
      PIN_NUMBER='(0,0,0,0,0,0,0,0,0,0,AT11)';
      PINUSE='POWER';
      NO_LOAD_CHECK='Both';
      NO_IO_CHECK='Both';
      NO_ASSERT_CHECK='TRUE';
      NO_DIR_CHECK='TRUE';
      ALLOW_CONNECT='TRUE';
    'VSS_AR32':
      PIN_NUMBER='(0,0,0,0,0,0,0,0,0,0,AR32)';
      PINUSE='POWER';
      NO_LOAD_CHECK='Both';
      NO_IO_CHECK='Both';
      NO_ASSERT_CHECK='TRUE';
      NO_DIR_CHECK='TRUE';
      ALLOW_CONNECT='TRUE';
    'VSS_AR20':
      PIN_NUMBER='(0,0,0,0,0,0,0,0,0,0,AR20)';
      PINUSE='POWER';
      NO_LOAD_CHECK='Both';
      NO_IO_CHECK='Both';
      NO_ASSERT_CHECK='TRUE';
      NO_DIR_CHECK='TRUE';
      ALLOW_CONNECT='TRUE';
    'VSS_AP5':
      PIN_NUMBER='(0,0,0,0,0,0,0,0,0,0,AP5)';
      PINUSE='POWER';
      NO_LOAD_CHECK='Both';
      NO_IO_CHECK='Both';
      NO_ASSERT_CHECK='TRUE';
      NO_DIR_CHECK='TRUE';
      ALLOW_CONNECT='TRUE';
    'VSS_AP39':
      PIN_NUMBER='(0,0,0,0,0,0,0,0,0,0,AP39)';
      PINUSE='POWER';
      NO_LOAD_CHECK='Both';
      NO_IO_CHECK='Both';
      NO_ASSERT_CHECK='TRUE';
      NO_DIR_CHECK='TRUE';
      ALLOW_CONNECT='TRUE';
    'VSS_AP37':
      PIN_NUMBER='(0,0,0,0,0,0,0,0,0,0,AP37)';
      PINUSE='POWER';
      NO_LOAD_CHECK='Both';
      NO_IO_CHECK='Both';
      NO_ASSERT_CHECK='TRUE';
      NO_DIR_CHECK='TRUE';
      ALLOW_CONNECT='TRUE';
    'VSS_AP28':
      PIN_NUMBER='(0,0,0,0,0,0,0,0,0,0,AP28)';
      PINUSE='POWER';
      NO_LOAD_CHECK='Both';
      NO_IO_CHECK='Both';
      NO_ASSERT_CHECK='TRUE';
      NO_DIR_CHECK='TRUE';
      ALLOW_CONNECT='TRUE';
    'VSS_AP24':
      PIN_NUMBER='(0,0,0,0,0,0,0,0,0,0,AP24)';
      PINUSE='POWER';
      NO_LOAD_CHECK='Both';
      NO_IO_CHECK='Both';
      NO_ASSERT_CHECK='TRUE';
      NO_DIR_CHECK='TRUE';
      ALLOW_CONNECT='TRUE';
    'VSS_AP18':
      PIN_NUMBER='(0,0,0,0,0,0,0,0,0,0,AP18)';
      PINUSE='POWER';
      NO_LOAD_CHECK='Both';
      NO_IO_CHECK='Both';
      NO_ASSERT_CHECK='TRUE';
      NO_DIR_CHECK='TRUE';
      ALLOW_CONNECT='TRUE';
    'VSS_AP11':
      PIN_NUMBER='(0,0,0,0,0,0,0,0,0,0,AP11)';
      PINUSE='POWER';
      NO_LOAD_CHECK='Both';
      NO_IO_CHECK='Both';
      NO_ASSERT_CHECK='TRUE';
      NO_DIR_CHECK='TRUE';
      ALLOW_CONNECT='TRUE';
    'VSS_AN32':
      PIN_NUMBER='(0,0,0,0,0,0,0,0,0,0,AN32)';
      PINUSE='POWER';
      NO_LOAD_CHECK='Both';
      NO_IO_CHECK='Both';
      NO_ASSERT_CHECK='TRUE';
      NO_DIR_CHECK='TRUE';
      ALLOW_CONNECT='TRUE';
    'VSS_AN29':
      PIN_NUMBER='(0,0,0,0,0,0,0,0,0,0,AN29)';
      PINUSE='POWER';
      NO_LOAD_CHECK='Both';
      NO_IO_CHECK='Both';
      NO_ASSERT_CHECK='TRUE';
      NO_DIR_CHECK='TRUE';
      ALLOW_CONNECT='TRUE';
    'VSS_AN16':
      PIN_NUMBER='(0,0,0,0,0,0,0,0,0,0,AN16)';
      PINUSE='POWER';
      NO_LOAD_CHECK='Both';
      NO_IO_CHECK='Both';
      NO_ASSERT_CHECK='TRUE';
      NO_DIR_CHECK='TRUE';
      ALLOW_CONNECT='TRUE';
    'VSS_AN13':
      PIN_NUMBER='(0,0,0,0,0,0,0,0,0,0,AN13)';
      PINUSE='POWER';
      NO_LOAD_CHECK='Both';
      NO_IO_CHECK='Both';
      NO_ASSERT_CHECK='TRUE';
      NO_DIR_CHECK='TRUE';
      ALLOW_CONNECT='TRUE';
    'VSS_AM8':
      PIN_NUMBER='(0,0,0,0,0,0,0,0,0,0,AM8)';
      PINUSE='POWER';
      NO_LOAD_CHECK='Both';
      NO_IO_CHECK='Both';
      NO_ASSERT_CHECK='TRUE';
      NO_DIR_CHECK='TRUE';
      ALLOW_CONNECT='TRUE';
    'VSS_AM31':
      PIN_NUMBER='(0,0,0,0,0,0,0,0,0,0,AM31)';
      PINUSE='POWER';
      NO_LOAD_CHECK='Both';
      NO_IO_CHECK='Both';
      NO_ASSERT_CHECK='TRUE';
      NO_DIR_CHECK='TRUE';
      ALLOW_CONNECT='TRUE';
    'VSS_AM15':
      PIN_NUMBER='(0,0,0,0,0,0,0,0,0,0,AM15)';
      PINUSE='POWER';
      NO_LOAD_CHECK='Both';
      NO_IO_CHECK='Both';
      NO_ASSERT_CHECK='TRUE';
      NO_DIR_CHECK='TRUE';
      ALLOW_CONNECT='TRUE';
    'VSS_AL39':
      PIN_NUMBER='(0,0,0,0,0,0,0,0,0,0,AL39)';
      PINUSE='POWER';
      NO_LOAD_CHECK='Both';
      NO_IO_CHECK='Both';
      NO_ASSERT_CHECK='TRUE';
      NO_DIR_CHECK='TRUE';
      ALLOW_CONNECT='TRUE';
    'VSS_AL29':
      PIN_NUMBER='(0,0,0,0,0,0,0,0,0,0,AL29)';
      PINUSE='POWER';
      NO_LOAD_CHECK='Both';
      NO_IO_CHECK='Both';
      NO_ASSERT_CHECK='TRUE';
      NO_DIR_CHECK='TRUE';
      ALLOW_CONNECT='TRUE';
    'VSS_AL27':
      PIN_NUMBER='(0,0,0,0,0,0,0,0,0,0,AL27)';
      PINUSE='POWER';
      NO_LOAD_CHECK='Both';
      NO_IO_CHECK='Both';
      NO_ASSERT_CHECK='TRUE';
      NO_DIR_CHECK='TRUE';
      ALLOW_CONNECT='TRUE';
    'VSS_AL24':
      PIN_NUMBER='(0,0,0,0,0,0,0,0,0,0,AL24)';
      PINUSE='POWER';
      NO_LOAD_CHECK='Both';
      NO_IO_CHECK='Both';
      NO_ASSERT_CHECK='TRUE';
      NO_DIR_CHECK='TRUE';
      ALLOW_CONNECT='TRUE';
    'VSS_AL19':
      PIN_NUMBER='(0,0,0,0,0,0,0,0,0,0,AL19)';
      PINUSE='POWER';
      NO_LOAD_CHECK='Both';
      NO_IO_CHECK='Both';
      NO_ASSERT_CHECK='TRUE';
      NO_DIR_CHECK='TRUE';
      ALLOW_CONNECT='TRUE';
    'VSS_AK4':
      PIN_NUMBER='(0,0,0,0,0,0,0,0,0,0,AK4)';
      PINUSE='POWER';
      NO_LOAD_CHECK='Both';
      NO_IO_CHECK='Both';
      NO_ASSERT_CHECK='TRUE';
      NO_DIR_CHECK='TRUE';
      ALLOW_CONNECT='TRUE';
    'VSS_AK37':
      PIN_NUMBER='(0,0,0,0,0,0,0,0,0,0,AK37)';
      PINUSE='POWER';
      NO_LOAD_CHECK='Both';
      NO_IO_CHECK='Both';
      NO_ASSERT_CHECK='TRUE';
      NO_DIR_CHECK='TRUE';
      ALLOW_CONNECT='TRUE';
    'VSS_AK2':
      PIN_NUMBER='(0,0,0,0,0,0,0,0,0,0,AK2)';
      PINUSE='POWER';
      NO_LOAD_CHECK='Both';
      NO_IO_CHECK='Both';
      NO_ASSERT_CHECK='TRUE';
      NO_DIR_CHECK='TRUE';
      ALLOW_CONNECT='TRUE';
    'VSS_AK11':
      PIN_NUMBER='(0,0,0,0,0,0,0,0,0,0,AK11)';
      PINUSE='POWER';
      NO_LOAD_CHECK='Both';
      NO_IO_CHECK='Both';
      NO_ASSERT_CHECK='TRUE';
      NO_DIR_CHECK='TRUE';
      ALLOW_CONNECT='TRUE';
    'VSS_AJ5':
      PIN_NUMBER='(0,0,0,0,0,0,0,0,0,0,AJ5)';
      PINUSE='POWER';
      NO_LOAD_CHECK='Both';
      NO_IO_CHECK='Both';
      NO_ASSERT_CHECK='TRUE';
      NO_DIR_CHECK='TRUE';
      ALLOW_CONNECT='TRUE';
    'VSS_AJ39':
      PIN_NUMBER='(0,0,0,0,0,0,0,0,0,0,AJ39)';
      PINUSE='POWER';
      NO_LOAD_CHECK='Both';
      NO_IO_CHECK='Both';
      NO_ASSERT_CHECK='TRUE';
      NO_DIR_CHECK='TRUE';
      ALLOW_CONNECT='TRUE';
    'VSS_AJ36':
      PIN_NUMBER='(0,0,0,0,0,0,0,0,0,0,AJ36)';
      PINUSE='POWER';
      NO_LOAD_CHECK='Both';
      NO_IO_CHECK='Both';
      NO_ASSERT_CHECK='TRUE';
      NO_DIR_CHECK='TRUE';
      ALLOW_CONNECT='TRUE';
    'VSS_AJ29':
      PIN_NUMBER='(0,0,0,0,0,0,0,0,0,0,AJ29)';
      PINUSE='POWER';
      NO_LOAD_CHECK='Both';
      NO_IO_CHECK='Both';
      NO_ASSERT_CHECK='TRUE';
      NO_DIR_CHECK='TRUE';
      ALLOW_CONNECT='TRUE';
    'VSS_AJ24':
      PIN_NUMBER='(0,0,0,0,0,0,0,0,0,0,AJ24)';
      PINUSE='POWER';
      NO_LOAD_CHECK='Both';
      NO_IO_CHECK='Both';
      NO_ASSERT_CHECK='TRUE';
      NO_DIR_CHECK='TRUE';
      ALLOW_CONNECT='TRUE';
    'VSS_AJ19':
      PIN_NUMBER='(0,0,0,0,0,0,0,0,0,0,AJ19)';
      PINUSE='POWER';
      NO_LOAD_CHECK='Both';
      NO_IO_CHECK='Both';
      NO_ASSERT_CHECK='TRUE';
      NO_DIR_CHECK='TRUE';
      ALLOW_CONNECT='TRUE';
    'VSS_AH8':
      PIN_NUMBER='(0,0,0,0,0,0,0,0,0,0,AH8)';
      PINUSE='POWER';
      NO_LOAD_CHECK='Both';
      NO_IO_CHECK='Both';
      NO_ASSERT_CHECK='TRUE';
      NO_DIR_CHECK='TRUE';
      ALLOW_CONNECT='TRUE';
    'VSS_AH31':
      PIN_NUMBER='(0,0,0,0,0,0,0,0,0,0,AH31)';
      PINUSE='POWER';
      NO_LOAD_CHECK='Both';
      NO_IO_CHECK='Both';
      NO_ASSERT_CHECK='TRUE';
      NO_DIR_CHECK='TRUE';
      ALLOW_CONNECT='TRUE';
    'VSS_AG5':
      PIN_NUMBER='(0,0,0,0,0,0,0,0,0,0,AG5)';
      PINUSE='POWER';
      NO_LOAD_CHECK='Both';
      NO_IO_CHECK='Both';
      NO_ASSERT_CHECK='TRUE';
      NO_DIR_CHECK='TRUE';
      ALLOW_CONNECT='TRUE';
    'VSS_AG39':
      PIN_NUMBER='(0,0,0,0,0,0,0,0,0,0,AG39)';
      PINUSE='POWER';
      NO_LOAD_CHECK='Both';
      NO_IO_CHECK='Both';
      NO_ASSERT_CHECK='TRUE';
      NO_DIR_CHECK='TRUE';
      ALLOW_CONNECT='TRUE';
    'VSS_AG24':
      PIN_NUMBER='(0,0,0,0,0,0,0,0,0,0,AG24)';
      PINUSE='POWER';
      NO_LOAD_CHECK='Both';
      NO_IO_CHECK='Both';
      NO_ASSERT_CHECK='TRUE';
      NO_DIR_CHECK='TRUE';
      ALLOW_CONNECT='TRUE';
    'VSS_AG19':
      PIN_NUMBER='(0,0,0,0,0,0,0,0,0,0,AG19)';
      PINUSE='POWER';
      NO_LOAD_CHECK='Both';
      NO_IO_CHECK='Both';
      NO_ASSERT_CHECK='TRUE';
      NO_DIR_CHECK='TRUE';
      ALLOW_CONNECT='TRUE';
    'VSS_AG13':
      PIN_NUMBER='(0,0,0,0,0,0,0,0,0,0,AG13)';
      PINUSE='POWER';
      NO_LOAD_CHECK='Both';
      NO_IO_CHECK='Both';
      NO_ASSERT_CHECK='TRUE';
      NO_DIR_CHECK='TRUE';
      ALLOW_CONNECT='TRUE';
    'VSS_AF42':
      PIN_NUMBER='(0,0,0,0,0,0,0,0,0,0,AF42)';
      PINUSE='POWER';
      NO_LOAD_CHECK='Both';
      NO_IO_CHECK='Both';
      NO_ASSERT_CHECK='TRUE';
      NO_DIR_CHECK='TRUE';
      ALLOW_CONNECT='TRUE';
    'VSS_AF40':
      PIN_NUMBER='(0,0,0,0,0,0,0,0,0,0,AF40)';
      PINUSE='POWER';
      NO_LOAD_CHECK='Both';
      NO_IO_CHECK='Both';
      NO_ASSERT_CHECK='TRUE';
      NO_DIR_CHECK='TRUE';
      ALLOW_CONNECT='TRUE';
    'VSS_AF31':
      PIN_NUMBER='(0,0,0,0,0,0,0,0,0,0,AF31)';
      PINUSE='POWER';
      NO_LOAD_CHECK='Both';
      NO_IO_CHECK='Both';
      NO_ASSERT_CHECK='TRUE';
      NO_DIR_CHECK='TRUE';
      ALLOW_CONNECT='TRUE';
    'VSS_AF24':
      PIN_NUMBER='(0,0,0,0,0,0,0,0,0,0,AF24)';
      PINUSE='POWER';
      NO_LOAD_CHECK='Both';
      NO_IO_CHECK='Both';
      NO_ASSERT_CHECK='TRUE';
      NO_DIR_CHECK='TRUE';
      ALLOW_CONNECT='TRUE';
    'VSS_AF19':
      PIN_NUMBER='(0,0,0,0,0,0,0,0,0,0,AF19)';
      PINUSE='POWER';
      NO_LOAD_CHECK='Both';
      NO_IO_CHECK='Both';
      NO_ASSERT_CHECK='TRUE';
      NO_DIR_CHECK='TRUE';
      ALLOW_CONNECT='TRUE';
    'VSS_AE5':
      PIN_NUMBER='(0,0,0,0,0,0,0,0,0,0,AE5)';
      PINUSE='POWER';
      NO_LOAD_CHECK='Both';
      NO_IO_CHECK='Both';
      NO_ASSERT_CHECK='TRUE';
      NO_DIR_CHECK='TRUE';
      ALLOW_CONNECT='TRUE';
    'VSS_AE39':
      PIN_NUMBER='(0,0,0,0,0,0,0,0,0,0,AE39)';
      PINUSE='POWER';
      NO_LOAD_CHECK='Both';
      NO_IO_CHECK='Both';
      NO_ASSERT_CHECK='TRUE';
      NO_DIR_CHECK='TRUE';
      ALLOW_CONNECT='TRUE';
    'VSS_AE13':
      PIN_NUMBER='(0,0,0,0,0,0,0,0,0,0,AE13)';
      PINUSE='POWER';
      NO_LOAD_CHECK='Both';
      NO_IO_CHECK='Both';
      NO_ASSERT_CHECK='TRUE';
      NO_DIR_CHECK='TRUE';
      ALLOW_CONNECT='TRUE';
    'VSS_AD8':
      PIN_NUMBER='(0,0,0,0,0,0,0,0,0,0,AD8)';
      PINUSE='POWER';
      NO_LOAD_CHECK='Both';
      NO_IO_CHECK='Both';
      NO_ASSERT_CHECK='TRUE';
      NO_DIR_CHECK='TRUE';
      ALLOW_CONNECT='TRUE';
    'VSS_AD34':
      PIN_NUMBER='(0,0,0,0,0,0,0,0,0,0,AD34)';
      PINUSE='POWER';
      NO_LOAD_CHECK='Both';
      NO_IO_CHECK='Both';
      NO_ASSERT_CHECK='TRUE';
      NO_DIR_CHECK='TRUE';
      ALLOW_CONNECT='TRUE';
    'VSS_AD31':
      PIN_NUMBER='(0,0,0,0,0,0,0,0,0,0,AD31)';
      PINUSE='POWER';
      NO_LOAD_CHECK='Both';
      NO_IO_CHECK='Both';
      NO_ASSERT_CHECK='TRUE';
      NO_DIR_CHECK='TRUE';
      ALLOW_CONNECT='TRUE';
    'VSS_AD24':
      PIN_NUMBER='(0,0,0,0,0,0,0,0,0,0,AD24)';
      PINUSE='POWER';
      NO_LOAD_CHECK='Both';
      NO_IO_CHECK='Both';
      NO_ASSERT_CHECK='TRUE';
      NO_DIR_CHECK='TRUE';
      ALLOW_CONNECT='TRUE';
    'VSS_AD22':
      PIN_NUMBER='(0,0,0,0,0,0,0,0,0,0,AD22)';
      PINUSE='POWER';
      NO_LOAD_CHECK='Both';
      NO_IO_CHECK='Both';
      NO_ASSERT_CHECK='TRUE';
      NO_DIR_CHECK='TRUE';
      ALLOW_CONNECT='TRUE';
    'VSS_AD20':
      PIN_NUMBER='(0,0,0,0,0,0,0,0,0,0,AD20)';
      PINUSE='POWER';
      NO_LOAD_CHECK='Both';
      NO_IO_CHECK='Both';
      NO_ASSERT_CHECK='TRUE';
      NO_DIR_CHECK='TRUE';
      ALLOW_CONNECT='TRUE';
    'VSS_AD19':
      PIN_NUMBER='(0,0,0,0,0,0,0,0,0,0,AD19)';
      PINUSE='POWER';
      NO_LOAD_CHECK='Both';
      NO_IO_CHECK='Both';
      NO_ASSERT_CHECK='TRUE';
      NO_DIR_CHECK='TRUE';
      ALLOW_CONNECT='TRUE';
    'VSS_AD11':
      PIN_NUMBER='(0,0,0,0,0,0,0,0,0,0,AD11)';
      PINUSE='POWER';
      NO_LOAD_CHECK='Both';
      NO_IO_CHECK='Both';
      NO_ASSERT_CHECK='TRUE';
      NO_DIR_CHECK='TRUE';
      ALLOW_CONNECT='TRUE';
    'VSS_AC5':
      PIN_NUMBER='(0,0,0,0,0,0,0,0,0,0,AC5)';
      PINUSE='POWER';
      NO_LOAD_CHECK='Both';
      NO_IO_CHECK='Both';
      NO_ASSERT_CHECK='TRUE';
      NO_DIR_CHECK='TRUE';
      ALLOW_CONNECT='TRUE';
    'VSS_AC39':
      PIN_NUMBER='(0,0,0,0,0,0,0,0,0,0,AC39)';
      PINUSE='POWER';
      NO_LOAD_CHECK='Both';
      NO_IO_CHECK='Both';
      NO_ASSERT_CHECK='TRUE';
      NO_DIR_CHECK='TRUE';
      ALLOW_CONNECT='TRUE';
    'VSS_AC36':
      PIN_NUMBER='(0,0,0,0,0,0,0,0,0,0,AC36)';
      PINUSE='POWER';
      NO_LOAD_CHECK='Both';
      NO_IO_CHECK='Both';
      NO_ASSERT_CHECK='TRUE';
      NO_DIR_CHECK='TRUE';
      ALLOW_CONNECT='TRUE';
    'VSS_AC32':
      PIN_NUMBER='(0,0,0,0,0,0,0,0,0,0,AC32)';
      PINUSE='POWER';
      NO_LOAD_CHECK='Both';
      NO_IO_CHECK='Both';
      NO_ASSERT_CHECK='TRUE';
      NO_DIR_CHECK='TRUE';
      ALLOW_CONNECT='TRUE';
    'VSS_AC29':
      PIN_NUMBER='(0,0,0,0,0,0,0,0,0,0,AC29)';
      PINUSE='POWER';
      NO_LOAD_CHECK='Both';
      NO_IO_CHECK='Both';
      NO_ASSERT_CHECK='TRUE';
      NO_DIR_CHECK='TRUE';
      ALLOW_CONNECT='TRUE';
    'VSS_AB37':
      PIN_NUMBER='(0,0,0,0,0,0,0,0,0,0,AB37)';
      PINUSE='POWER';
      NO_LOAD_CHECK='Both';
      NO_IO_CHECK='Both';
      NO_ASSERT_CHECK='TRUE';
      NO_DIR_CHECK='TRUE';
      ALLOW_CONNECT='TRUE';
    'VSS_AB25':
      PIN_NUMBER='(0,0,0,0,0,0,0,0,0,0,AB25)';
      PINUSE='POWER';
      NO_LOAD_CHECK='Both';
      NO_IO_CHECK='Both';
      NO_ASSERT_CHECK='TRUE';
      NO_DIR_CHECK='TRUE';
      ALLOW_CONNECT='TRUE';
    'VSS_AB17':
      PIN_NUMBER='(0,0,0,0,0,0,0,0,0,0,AB17)';
      PINUSE='POWER';
      NO_LOAD_CHECK='Both';
      NO_IO_CHECK='Both';
      NO_ASSERT_CHECK='TRUE';
      NO_DIR_CHECK='TRUE';
      ALLOW_CONNECT='TRUE';
    'VSS_AB15':
      PIN_NUMBER='(0,0,0,0,0,0,0,0,0,0,AB15)';
      PINUSE='POWER';
      NO_LOAD_CHECK='Both';
      NO_IO_CHECK='Both';
      NO_ASSERT_CHECK='TRUE';
      NO_DIR_CHECK='TRUE';
      ALLOW_CONNECT='TRUE';
    'VSS_AA5':
      PIN_NUMBER='(0,0,0,0,0,0,0,0,0,0,AA5)';
      PINUSE='POWER';
      NO_LOAD_CHECK='Both';
      NO_IO_CHECK='Both';
      NO_ASSERT_CHECK='TRUE';
      NO_DIR_CHECK='TRUE';
      ALLOW_CONNECT='TRUE';
    'VSS_AA39':
      PIN_NUMBER='(0,0,0,0,0,0,0,0,0,0,AA39)';
      PINUSE='POWER';
      NO_LOAD_CHECK='Both';
      NO_IO_CHECK='Both';
      NO_ASSERT_CHECK='TRUE';
      NO_DIR_CHECK='TRUE';
      ALLOW_CONNECT='TRUE';
    'VSS_AA36':
      PIN_NUMBER='(0,0,0,0,0,0,0,0,0,0,AA36)';
      PINUSE='POWER';
      NO_LOAD_CHECK='Both';
      NO_IO_CHECK='Both';
      NO_ASSERT_CHECK='TRUE';
      NO_DIR_CHECK='TRUE';
      ALLOW_CONNECT='TRUE';
    'VSS_AA32':
      PIN_NUMBER='(0,0,0,0,0,0,0,0,0,0,AA32)';
      PINUSE='POWER';
      NO_LOAD_CHECK='Both';
      NO_IO_CHECK='Both';
      NO_ASSERT_CHECK='TRUE';
      NO_DIR_CHECK='TRUE';
      ALLOW_CONNECT='TRUE';
    'VSS_AA27':
      PIN_NUMBER='(0,0,0,0,0,0,0,0,0,0,AA27)';
      PINUSE='POWER';
      NO_LOAD_CHECK='Both';
      NO_IO_CHECK='Both';
      NO_ASSERT_CHECK='TRUE';
      NO_DIR_CHECK='TRUE';
      ALLOW_CONNECT='TRUE';
    'VSS_AA25':
      PIN_NUMBER='(0,0,0,0,0,0,0,0,0,0,AA25)';
      PINUSE='POWER';
      NO_LOAD_CHECK='Both';
      NO_IO_CHECK='Both';
      NO_ASSERT_CHECK='TRUE';
      NO_DIR_CHECK='TRUE';
      ALLOW_CONNECT='TRUE';
    'VSS_AA24':
      PIN_NUMBER='(0,0,0,0,0,0,0,0,0,0,AA24)';
      PINUSE='POWER';
      NO_LOAD_CHECK='Both';
      NO_IO_CHECK='Both';
      NO_ASSERT_CHECK='TRUE';
      NO_DIR_CHECK='TRUE';
      ALLOW_CONNECT='TRUE';
    'VSS_AA22':
      PIN_NUMBER='(0,0,0,0,0,0,0,0,0,0,AA22)';
      PINUSE='POWER';
      NO_LOAD_CHECK='Both';
      NO_IO_CHECK='Both';
      NO_ASSERT_CHECK='TRUE';
      NO_DIR_CHECK='TRUE';
      ALLOW_CONNECT='TRUE';
    'VSS_AA20':
      PIN_NUMBER='(0,0,0,0,0,0,0,0,0,0,AA20)';
      PINUSE='POWER';
      NO_LOAD_CHECK='Both';
      NO_IO_CHECK='Both';
      NO_ASSERT_CHECK='TRUE';
      NO_DIR_CHECK='TRUE';
      ALLOW_CONNECT='TRUE';
    'VSS_AA19':
      PIN_NUMBER='(0,0,0,0,0,0,0,0,0,0,AA19)';
      PINUSE='POWER';
      NO_LOAD_CHECK='Both';
      NO_IO_CHECK='Both';
      NO_ASSERT_CHECK='TRUE';
      NO_DIR_CHECK='TRUE';
      ALLOW_CONNECT='TRUE';
    'VSS_AA17':
      PIN_NUMBER='(0,0,0,0,0,0,0,0,0,0,AA17)';
      PINUSE='POWER';
      NO_LOAD_CHECK='Both';
      NO_IO_CHECK='Both';
      NO_ASSERT_CHECK='TRUE';
      NO_DIR_CHECK='TRUE';
      ALLOW_CONNECT='TRUE';
    'VSS_A26':
      PIN_NUMBER='(0,0,0,0,0,0,0,0,0,0,A26)';
      PINUSE='POWER';
      NO_LOAD_CHECK='Both';
      NO_IO_CHECK='Both';
      NO_ASSERT_CHECK='TRUE';
      NO_DIR_CHECK='TRUE';
      ALLOW_CONNECT='TRUE';
    'VSS_A24':
      PIN_NUMBER='(0,0,0,0,0,0,0,0,0,0,A24)';
      PINUSE='POWER';
      NO_LOAD_CHECK='Both';
      NO_IO_CHECK='Both';
      NO_ASSERT_CHECK='TRUE';
      NO_DIR_CHECK='TRUE';
      ALLOW_CONNECT='TRUE';
    'VSS_A22':
      PIN_NUMBER='(0,0,0,0,0,0,0,0,0,0,A22)';
      PINUSE='POWER';
      NO_LOAD_CHECK='Both';
      NO_IO_CHECK='Both';
      NO_ASSERT_CHECK='TRUE';
      NO_DIR_CHECK='TRUE';
      ALLOW_CONNECT='TRUE';
    'VSS_A20':
      PIN_NUMBER='(0,0,0,0,0,0,0,0,0,0,A20)';
      PINUSE='POWER';
      NO_LOAD_CHECK='Both';
      NO_IO_CHECK='Both';
      NO_ASSERT_CHECK='TRUE';
      NO_DIR_CHECK='TRUE';
      ALLOW_CONNECT='TRUE';
  end_pin;
  body
    PART_NAME='Emmitsburg_rev0p9';
    BODY_NAME='EMMITSBURG_REV0P9';
    PHYS_DES_PREFIX='U';
    CLASS='IC';
  end_body;
end_primitive;

END.
